FILE_TYPE = MACRO_DRAWING;
SET COLOR_WIRE YELLOW;
SET COLOR_PROP ORANGE;
SET COLOR_DOT WHITE;
SET COLOR_ARC YELLOW;
SET COLOR_BODY GREEN;
SET COLOR_NOTE PURPLE;
SET PROP_DISPLAY VALUE;
SET PAGE_NUMBER P91;
FORCEADD OFFPAGE..5
(-7925 1950);
FORCEPROP 2 LAST $XR0 16 
J 0
(-8149 1950);
DISPLAY 0.638298 (-8149 1950);
PAINT MONO (-8149 1950);
FORCEPROP 2 LAST CDS_LIB mstr_standard
J 0
(-7925 1950);
DISPLAY 0.808511 (-7925 1950);
DISPLAY INVISIBLE (-7925 1950);
FORCEPROP 1 LAST OFFPAGE TRUE
J 0
(-7600 1825);
DISPLAY 0.872340 (-7600 1825);
PAINT GREEN (-7600 1825);
DISPLAY INVISIBLE (-7600 1825);
FORCEPROP 1 LAST COMMENT_BODY TRUE
J 0
(-7825 1875);
DISPLAY 0.872340 (-7825 1875);
PAINT GREEN (-7825 1875);
DISPLAY INVISIBLE (-7825 1875);
FORCEPROP 2 LAST PATH I1
J 0
(-8125 2000);
DISPLAY 1.021277 (-8125 2000);
DISPLAY INVISIBLE (-8125 2000);
FORCEADD OFFPAGE..6
(-7925 3600);
FORCEPROP 2 LAST $XR0 16 
J 0
(-8204 3600);
DISPLAY 0.638298 (-8204 3600);
PAINT MONO (-8204 3600);
FORCEPROP 2 LAST CDS_LIB mstr_standard
J 0
(-7925 3600);
DISPLAY 0.723404 (-7925 3600);
PAINT MONO (-7925 3600);
DISPLAY INVISIBLE (-7925 3600);
FORCEPROP 1 LAST OFFPAGE TRUE
J 0
(-7600 3475);
DISPLAY 0.872340 (-7600 3475);
PAINT GREEN (-7600 3475);
DISPLAY INVISIBLE (-7600 3475);
FORCEPROP 1 LAST COMMENT_BODY TRUE
J 0
(-7825 3525);
DISPLAY 0.872340 (-7825 3525);
PAINT GREEN (-7825 3525);
DISPLAY INVISIBLE (-7825 3525);
FORCEPROP 2 LAST PATH I10
J 0
(-8200 3650);
DISPLAY 1.021277 (-8200 3650);
DISPLAY INVISIBLE (-8200 3650);
FORCEADD TAP..1
(-5625 4100);
FORCEPROP 3 LASTPIN (-5675 4100) SIG_NAME M_G_CPU0_SA_DQ<5>
J 0
(-5665 4110);
DISPLAY 0.659574 (-5665 4110);
PAINT MONO (-5665 4110);
DISPLAY INVISIBLE (-5665 4110);
FORCEPROP 1 LASTPIN (-5675 4100) BN 5
J 0
(-5687 4108);
DISPLAY 0.489362 (-5687 4108);
PAINT GREEN (-5687 4108);
FORCEPROP 2 LAST CDS_LIB mstr_standard
J 0
(-5625 4100);
DISPLAY 0.723404 (-5625 4100);
PAINT MONO (-5625 4100);
DISPLAY INVISIBLE (-5625 4100);
FORCEPROP 1 LAST BODY_TYPE PLUMBING
J 0
(-5625 4150);
DISPLAY 0.872340 (-5625 4150);
PAINT GREEN (-5625 4150);
DISPLAY INVISIBLE (-5625 4150);
FORCEPROP 1 LAST HDL_TAP TRUE
J 0
(-5300 3975);
DISPLAY 0.872340 (-5300 3975);
DISPLAY INVISIBLE (-5300 3975);
FORCEPROP 1 LAST PATH I100
J 0
(-5627 4100);
DISPLAY 0.872340 (-5627 4100);
PAINT GREEN (-5627 4100);
DISPLAY INVISIBLE (-5627 4100);
FORCEADD TAP..1
(-5625 4250);
FORCEPROP 3 LASTPIN (-5675 4250) SIG_NAME M_G_CPU0_SA_DQ<8>
J 0
(-5665 4260);
DISPLAY 0.659574 (-5665 4260);
PAINT MONO (-5665 4260);
DISPLAY INVISIBLE (-5665 4260);
FORCEPROP 1 LASTPIN (-5675 4250) BN 8
J 0
(-5687 4258);
DISPLAY 0.489362 (-5687 4258);
PAINT GREEN (-5687 4258);
FORCEPROP 2 LAST CDS_LIB mstr_standard
J 0
(-5625 4250);
DISPLAY 0.723404 (-5625 4250);
PAINT MONO (-5625 4250);
DISPLAY INVISIBLE (-5625 4250);
FORCEPROP 1 LAST BODY_TYPE PLUMBING
J 0
(-5625 4300);
DISPLAY 0.872340 (-5625 4300);
PAINT GREEN (-5625 4300);
DISPLAY INVISIBLE (-5625 4300);
FORCEPROP 1 LAST HDL_TAP TRUE
J 0
(-5300 4125);
DISPLAY 0.872340 (-5300 4125);
DISPLAY INVISIBLE (-5300 4125);
FORCEPROP 1 LAST PATH I101
J 0
(-5627 4250);
DISPLAY 0.872340 (-5627 4250);
PAINT GREEN (-5627 4250);
DISPLAY INVISIBLE (-5627 4250);
FORCEADD TAP..1
(-5625 4300);
FORCEPROP 3 LASTPIN (-5675 4300) SIG_NAME M_G_CPU0_SA_DQ<9>
J 0
(-5665 4310);
DISPLAY 0.659574 (-5665 4310);
PAINT MONO (-5665 4310);
DISPLAY INVISIBLE (-5665 4310);
FORCEPROP 1 LASTPIN (-5675 4300) BN 9
J 0
(-5687 4308);
DISPLAY 0.489362 (-5687 4308);
PAINT GREEN (-5687 4308);
FORCEPROP 2 LAST CDS_LIB mstr_standard
J 0
(-5625 4300);
DISPLAY 0.723404 (-5625 4300);
PAINT MONO (-5625 4300);
DISPLAY INVISIBLE (-5625 4300);
FORCEPROP 1 LAST BODY_TYPE PLUMBING
J 0
(-5625 4350);
DISPLAY 0.872340 (-5625 4350);
PAINT GREEN (-5625 4350);
DISPLAY INVISIBLE (-5625 4350);
FORCEPROP 1 LAST HDL_TAP TRUE
J 0
(-5300 4175);
DISPLAY 0.872340 (-5300 4175);
DISPLAY INVISIBLE (-5300 4175);
FORCEPROP 1 LAST PATH I102
J 0
(-5627 4300);
DISPLAY 0.872340 (-5627 4300);
PAINT GREEN (-5627 4300);
DISPLAY INVISIBLE (-5627 4300);
FORCEADD TAP..1
(-5625 4200);
FORCEPROP 3 LASTPIN (-5675 4200) SIG_NAME M_G_CPU0_SA_DQ<7>
J 0
(-5665 4210);
DISPLAY 0.659574 (-5665 4210);
PAINT MONO (-5665 4210);
DISPLAY INVISIBLE (-5665 4210);
FORCEPROP 1 LASTPIN (-5675 4200) BN 7
J 0
(-5687 4208);
DISPLAY 0.489362 (-5687 4208);
PAINT GREEN (-5687 4208);
FORCEPROP 2 LAST CDS_LIB mstr_standard
J 0
(-5625 4200);
DISPLAY 0.723404 (-5625 4200);
PAINT MONO (-5625 4200);
DISPLAY INVISIBLE (-5625 4200);
FORCEPROP 1 LAST BODY_TYPE PLUMBING
J 0
(-5625 4250);
DISPLAY 0.872340 (-5625 4250);
PAINT GREEN (-5625 4250);
DISPLAY INVISIBLE (-5625 4250);
FORCEPROP 1 LAST HDL_TAP TRUE
J 0
(-5300 4075);
DISPLAY 0.872340 (-5300 4075);
DISPLAY INVISIBLE (-5300 4075);
FORCEPROP 1 LAST PATH I103
J 0
(-5627 4200);
DISPLAY 0.872340 (-5627 4200);
PAINT GREEN (-5627 4200);
DISPLAY INVISIBLE (-5627 4200);
FORCEADD TAP..1
(-5625 4450);
FORCEPROP 3 LASTPIN (-5675 4450) SIG_NAME M_G_CPU0_SA_DQ<12>
J 0
(-5665 4460);
DISPLAY 0.659574 (-5665 4460);
PAINT MONO (-5665 4460);
DISPLAY INVISIBLE (-5665 4460);
FORCEPROP 1 LASTPIN (-5675 4450) BN 12
J 0
(-5687 4458);
DISPLAY 0.489362 (-5687 4458);
PAINT GREEN (-5687 4458);
FORCEPROP 2 LAST CDS_LIB mstr_standard
J 0
(-5625 4450);
DISPLAY 0.723404 (-5625 4450);
PAINT MONO (-5625 4450);
DISPLAY INVISIBLE (-5625 4450);
FORCEPROP 1 LAST BODY_TYPE PLUMBING
J 0
(-5625 4500);
DISPLAY 0.872340 (-5625 4500);
PAINT GREEN (-5625 4500);
DISPLAY INVISIBLE (-5625 4500);
FORCEPROP 1 LAST HDL_TAP TRUE
J 0
(-5300 4325);
DISPLAY 0.872340 (-5300 4325);
DISPLAY INVISIBLE (-5300 4325);
FORCEPROP 1 LAST PATH I104
J 0
(-5627 4450);
DISPLAY 0.872340 (-5627 4450);
PAINT GREEN (-5627 4450);
DISPLAY INVISIBLE (-5627 4450);
FORCEADD TAP..1
(-5625 4400);
FORCEPROP 3 LASTPIN (-5675 4400) SIG_NAME M_G_CPU0_SA_DQ<11>
J 0
(-5665 4410);
DISPLAY 0.659574 (-5665 4410);
PAINT MONO (-5665 4410);
DISPLAY INVISIBLE (-5665 4410);
FORCEPROP 1 LASTPIN (-5675 4400) BN 11
J 0
(-5687 4408);
DISPLAY 0.489362 (-5687 4408);
PAINT GREEN (-5687 4408);
FORCEPROP 2 LAST CDS_LIB mstr_standard
J 0
(-5625 4400);
DISPLAY 0.723404 (-5625 4400);
PAINT MONO (-5625 4400);
DISPLAY INVISIBLE (-5625 4400);
FORCEPROP 1 LAST BODY_TYPE PLUMBING
J 0
(-5625 4450);
DISPLAY 0.872340 (-5625 4450);
PAINT GREEN (-5625 4450);
DISPLAY INVISIBLE (-5625 4450);
FORCEPROP 1 LAST HDL_TAP TRUE
J 0
(-5300 4275);
DISPLAY 0.872340 (-5300 4275);
DISPLAY INVISIBLE (-5300 4275);
FORCEPROP 1 LAST PATH I105
J 0
(-5627 4400);
DISPLAY 0.872340 (-5627 4400);
PAINT GREEN (-5627 4400);
DISPLAY INVISIBLE (-5627 4400);
FORCEADD TAP..1
(-5625 4350);
FORCEPROP 3 LASTPIN (-5675 4350) SIG_NAME M_G_CPU0_SA_DQ<10>
J 0
(-5665 4360);
DISPLAY 0.659574 (-5665 4360);
PAINT MONO (-5665 4360);
DISPLAY INVISIBLE (-5665 4360);
FORCEPROP 1 LASTPIN (-5675 4350) BN 10
J 0
(-5687 4358);
DISPLAY 0.489362 (-5687 4358);
PAINT GREEN (-5687 4358);
FORCEPROP 2 LAST CDS_LIB mstr_standard
J 0
(-5625 4350);
DISPLAY 0.723404 (-5625 4350);
PAINT MONO (-5625 4350);
DISPLAY INVISIBLE (-5625 4350);
FORCEPROP 1 LAST BODY_TYPE PLUMBING
J 0
(-5625 4400);
DISPLAY 0.872340 (-5625 4400);
PAINT GREEN (-5625 4400);
DISPLAY INVISIBLE (-5625 4400);
FORCEPROP 1 LAST HDL_TAP TRUE
J 0
(-5300 4225);
DISPLAY 0.872340 (-5300 4225);
DISPLAY INVISIBLE (-5300 4225);
FORCEPROP 1 LAST PATH I106
J 0
(-5627 4350);
DISPLAY 0.872340 (-5627 4350);
PAINT GREEN (-5627 4350);
DISPLAY INVISIBLE (-5627 4350);
FORCEADD TAP..1
(-5625 4500);
FORCEPROP 3 LASTPIN (-5675 4500) SIG_NAME M_G_CPU0_SA_DQ<13>
J 0
(-5665 4510);
DISPLAY 0.659574 (-5665 4510);
PAINT MONO (-5665 4510);
DISPLAY INVISIBLE (-5665 4510);
FORCEPROP 1 LASTPIN (-5675 4500) BN 13
J 0
(-5687 4508);
DISPLAY 0.489362 (-5687 4508);
PAINT GREEN (-5687 4508);
FORCEPROP 2 LAST CDS_LIB mstr_standard
J 0
(-5625 4500);
DISPLAY 0.723404 (-5625 4500);
PAINT MONO (-5625 4500);
DISPLAY INVISIBLE (-5625 4500);
FORCEPROP 1 LAST BODY_TYPE PLUMBING
J 0
(-5625 4550);
DISPLAY 0.872340 (-5625 4550);
PAINT GREEN (-5625 4550);
DISPLAY INVISIBLE (-5625 4550);
FORCEPROP 1 LAST HDL_TAP TRUE
J 0
(-5300 4375);
DISPLAY 0.872340 (-5300 4375);
DISPLAY INVISIBLE (-5300 4375);
FORCEPROP 1 LAST PATH I107
J 0
(-5627 4500);
DISPLAY 0.872340 (-5627 4500);
PAINT GREEN (-5627 4500);
DISPLAY INVISIBLE (-5627 4500);
FORCEADD TAP..1
(-5625 4550);
FORCEPROP 3 LASTPIN (-5675 4550) SIG_NAME M_G_CPU0_SA_DQ<14>
J 0
(-5665 4560);
DISPLAY 0.659574 (-5665 4560);
PAINT MONO (-5665 4560);
DISPLAY INVISIBLE (-5665 4560);
FORCEPROP 1 LASTPIN (-5675 4550) BN 14
J 0
(-5687 4558);
DISPLAY 0.489362 (-5687 4558);
PAINT GREEN (-5687 4558);
FORCEPROP 2 LAST CDS_LIB mstr_standard
J 0
(-5625 4550);
DISPLAY 0.723404 (-5625 4550);
PAINT MONO (-5625 4550);
DISPLAY INVISIBLE (-5625 4550);
FORCEPROP 1 LAST BODY_TYPE PLUMBING
J 0
(-5625 4600);
DISPLAY 0.872340 (-5625 4600);
PAINT GREEN (-5625 4600);
DISPLAY INVISIBLE (-5625 4600);
FORCEPROP 1 LAST HDL_TAP TRUE
J 0
(-5300 4425);
DISPLAY 0.872340 (-5300 4425);
DISPLAY INVISIBLE (-5300 4425);
FORCEPROP 1 LAST PATH I108
J 0
(-5627 4550);
DISPLAY 0.872340 (-5627 4550);
PAINT GREEN (-5627 4550);
DISPLAY INVISIBLE (-5627 4550);
FORCEADD TAP..1
(-5625 4700);
FORCEPROP 3 LASTPIN (-5675 4700) SIG_NAME M_G_CPU0_SA_DQ<17>
J 0
(-5665 4710);
DISPLAY 0.659574 (-5665 4710);
PAINT MONO (-5665 4710);
DISPLAY INVISIBLE (-5665 4710);
FORCEPROP 1 LASTPIN (-5675 4700) BN 17
J 0
(-5687 4708);
DISPLAY 0.489362 (-5687 4708);
PAINT GREEN (-5687 4708);
FORCEPROP 2 LAST CDS_LIB mstr_standard
J 0
(-5625 4700);
DISPLAY 0.723404 (-5625 4700);
PAINT MONO (-5625 4700);
DISPLAY INVISIBLE (-5625 4700);
FORCEPROP 1 LAST BODY_TYPE PLUMBING
J 0
(-5625 4750);
DISPLAY 0.872340 (-5625 4750);
PAINT GREEN (-5625 4750);
DISPLAY INVISIBLE (-5625 4750);
FORCEPROP 1 LAST HDL_TAP TRUE
J 0
(-5300 4575);
DISPLAY 0.872340 (-5300 4575);
DISPLAY INVISIBLE (-5300 4575);
FORCEPROP 1 LAST PATH I109
J 0
(-5627 4700);
DISPLAY 0.872340 (-5627 4700);
PAINT GREEN (-5627 4700);
DISPLAY INVISIBLE (-5627 4700);
FORCEADD OFFPAGE..6
(-7925 4050);
FORCEPROP 2 LAST $XR0 16 
J 0
(-8204 4050);
DISPLAY 0.638298 (-8204 4050);
PAINT MONO (-8204 4050);
FORCEPROP 2 LAST CDS_LIB mstr_standard
J 0
(-7925 4050);
DISPLAY 0.723404 (-7925 4050);
PAINT MONO (-7925 4050);
DISPLAY INVISIBLE (-7925 4050);
FORCEPROP 1 LAST OFFPAGE TRUE
J 0
(-7600 3925);
DISPLAY 0.872340 (-7600 3925);
PAINT GREEN (-7600 3925);
DISPLAY INVISIBLE (-7600 3925);
FORCEPROP 1 LAST COMMENT_BODY TRUE
J 0
(-7825 3975);
DISPLAY 0.872340 (-7825 3975);
PAINT GREEN (-7825 3975);
DISPLAY INVISIBLE (-7825 3975);
FORCEPROP 2 LAST PATH I11
J 0
(-8200 4100);
DISPLAY 1.021277 (-8200 4100);
DISPLAY INVISIBLE (-8200 4100);
FORCEADD TAP..1
(-5625 4650);
FORCEPROP 3 LASTPIN (-5675 4650) SIG_NAME M_G_CPU0_SA_DQ<16>
J 0
(-5665 4660);
DISPLAY 0.659574 (-5665 4660);
PAINT MONO (-5665 4660);
DISPLAY INVISIBLE (-5665 4660);
FORCEPROP 1 LASTPIN (-5675 4650) BN 16
J 0
(-5687 4658);
DISPLAY 0.489362 (-5687 4658);
PAINT GREEN (-5687 4658);
FORCEPROP 2 LAST CDS_LIB mstr_standard
J 0
(-5625 4650);
DISPLAY 0.723404 (-5625 4650);
PAINT MONO (-5625 4650);
DISPLAY INVISIBLE (-5625 4650);
FORCEPROP 1 LAST BODY_TYPE PLUMBING
J 0
(-5625 4700);
DISPLAY 0.872340 (-5625 4700);
PAINT GREEN (-5625 4700);
DISPLAY INVISIBLE (-5625 4700);
FORCEPROP 1 LAST HDL_TAP TRUE
J 0
(-5300 4525);
DISPLAY 0.872340 (-5300 4525);
DISPLAY INVISIBLE (-5300 4525);
FORCEPROP 1 LAST PATH I110
J 0
(-5627 4650);
DISPLAY 0.872340 (-5627 4650);
PAINT GREEN (-5627 4650);
DISPLAY INVISIBLE (-5627 4650);
FORCEADD TAP..1
(-5625 4600);
FORCEPROP 3 LASTPIN (-5675 4600) SIG_NAME M_G_CPU0_SA_DQ<15>
J 0
(-5665 4610);
DISPLAY 0.659574 (-5665 4610);
PAINT MONO (-5665 4610);
DISPLAY INVISIBLE (-5665 4610);
FORCEPROP 1 LASTPIN (-5675 4600) BN 15
J 0
(-5687 4608);
DISPLAY 0.489362 (-5687 4608);
PAINT GREEN (-5687 4608);
FORCEPROP 2 LAST CDS_LIB mstr_standard
J 0
(-5625 4600);
DISPLAY 0.723404 (-5625 4600);
PAINT MONO (-5625 4600);
DISPLAY INVISIBLE (-5625 4600);
FORCEPROP 1 LAST BODY_TYPE PLUMBING
J 0
(-5625 4650);
DISPLAY 0.872340 (-5625 4650);
PAINT GREEN (-5625 4650);
DISPLAY INVISIBLE (-5625 4650);
FORCEPROP 1 LAST HDL_TAP TRUE
J 0
(-5300 4475);
DISPLAY 0.872340 (-5300 4475);
DISPLAY INVISIBLE (-5300 4475);
FORCEPROP 1 LAST PATH I111
J 0
(-5627 4600);
DISPLAY 0.872340 (-5627 4600);
PAINT GREEN (-5627 4600);
DISPLAY INVISIBLE (-5627 4600);
FORCEADD TAP..1
(-5625 4750);
FORCEPROP 3 LASTPIN (-5675 4750) SIG_NAME M_G_CPU0_SA_DQ<18>
J 0
(-5665 4760);
DISPLAY 0.659574 (-5665 4760);
PAINT MONO (-5665 4760);
DISPLAY INVISIBLE (-5665 4760);
FORCEPROP 1 LASTPIN (-5675 4750) BN 18
J 0
(-5687 4758);
DISPLAY 0.489362 (-5687 4758);
PAINT GREEN (-5687 4758);
FORCEPROP 2 LAST CDS_LIB mstr_standard
J 0
(-5625 4750);
DISPLAY 0.723404 (-5625 4750);
PAINT MONO (-5625 4750);
DISPLAY INVISIBLE (-5625 4750);
FORCEPROP 1 LAST BODY_TYPE PLUMBING
J 0
(-5625 4800);
DISPLAY 0.872340 (-5625 4800);
PAINT GREEN (-5625 4800);
DISPLAY INVISIBLE (-5625 4800);
FORCEPROP 1 LAST HDL_TAP TRUE
J 0
(-5300 4625);
DISPLAY 0.872340 (-5300 4625);
DISPLAY INVISIBLE (-5300 4625);
FORCEPROP 1 LAST PATH I112
J 0
(-5627 4750);
DISPLAY 0.872340 (-5627 4750);
PAINT GREEN (-5627 4750);
DISPLAY INVISIBLE (-5627 4750);
FORCEADD TAP..1
(-5625 4800);
FORCEPROP 3 LASTPIN (-5675 4800) SIG_NAME M_G_CPU0_SA_DQ<19>
J 0
(-5665 4810);
DISPLAY 0.659574 (-5665 4810);
PAINT MONO (-5665 4810);
DISPLAY INVISIBLE (-5665 4810);
FORCEPROP 1 LASTPIN (-5675 4800) BN 19
J 0
(-5687 4808);
DISPLAY 0.489362 (-5687 4808);
PAINT GREEN (-5687 4808);
FORCEPROP 2 LAST CDS_LIB mstr_standard
J 0
(-5625 4800);
DISPLAY 0.723404 (-5625 4800);
PAINT MONO (-5625 4800);
DISPLAY INVISIBLE (-5625 4800);
FORCEPROP 1 LAST BODY_TYPE PLUMBING
J 0
(-5625 4850);
DISPLAY 0.872340 (-5625 4850);
PAINT GREEN (-5625 4850);
DISPLAY INVISIBLE (-5625 4850);
FORCEPROP 1 LAST HDL_TAP TRUE
J 0
(-5300 4675);
DISPLAY 0.872340 (-5300 4675);
DISPLAY INVISIBLE (-5300 4675);
FORCEPROP 1 LAST PATH I113
J 0
(-5627 4800);
DISPLAY 0.872340 (-5627 4800);
PAINT GREEN (-5627 4800);
DISPLAY INVISIBLE (-5627 4800);
FORCEADD TAP..1
(-5625 4950);
FORCEPROP 3 LASTPIN (-5675 4950) SIG_NAME M_G_CPU0_SA_DQ<22>
J 0
(-5665 4960);
DISPLAY 0.659574 (-5665 4960);
PAINT MONO (-5665 4960);
DISPLAY INVISIBLE (-5665 4960);
FORCEPROP 1 LASTPIN (-5675 4950) BN 22
J 0
(-5687 4958);
DISPLAY 0.489362 (-5687 4958);
PAINT GREEN (-5687 4958);
FORCEPROP 2 LAST CDS_LIB mstr_standard
J 0
(-5625 4950);
DISPLAY 0.723404 (-5625 4950);
PAINT MONO (-5625 4950);
DISPLAY INVISIBLE (-5625 4950);
FORCEPROP 1 LAST BODY_TYPE PLUMBING
J 0
(-5625 5000);
DISPLAY 0.872340 (-5625 5000);
PAINT GREEN (-5625 5000);
DISPLAY INVISIBLE (-5625 5000);
FORCEPROP 1 LAST HDL_TAP TRUE
J 0
(-5300 4825);
DISPLAY 0.872340 (-5300 4825);
DISPLAY INVISIBLE (-5300 4825);
FORCEPROP 1 LAST PATH I114
J 0
(-5627 4950);
DISPLAY 0.872340 (-5627 4950);
PAINT GREEN (-5627 4950);
DISPLAY INVISIBLE (-5627 4950);
FORCEADD TAP..1
(-5625 4900);
FORCEPROP 3 LASTPIN (-5675 4900) SIG_NAME M_G_CPU0_SA_DQ<21>
J 0
(-5665 4910);
DISPLAY 0.659574 (-5665 4910);
PAINT MONO (-5665 4910);
DISPLAY INVISIBLE (-5665 4910);
FORCEPROP 1 LASTPIN (-5675 4900) BN 21
J 0
(-5687 4908);
DISPLAY 0.489362 (-5687 4908);
PAINT GREEN (-5687 4908);
FORCEPROP 2 LAST CDS_LIB mstr_standard
J 0
(-5625 4900);
DISPLAY 0.723404 (-5625 4900);
PAINT MONO (-5625 4900);
DISPLAY INVISIBLE (-5625 4900);
FORCEPROP 1 LAST BODY_TYPE PLUMBING
J 0
(-5625 4950);
DISPLAY 0.872340 (-5625 4950);
PAINT GREEN (-5625 4950);
DISPLAY INVISIBLE (-5625 4950);
FORCEPROP 1 LAST HDL_TAP TRUE
J 0
(-5300 4775);
DISPLAY 0.872340 (-5300 4775);
DISPLAY INVISIBLE (-5300 4775);
FORCEPROP 1 LAST PATH I115
J 0
(-5627 4900);
DISPLAY 0.872340 (-5627 4900);
PAINT GREEN (-5627 4900);
DISPLAY INVISIBLE (-5627 4900);
FORCEADD TAP..1
(-5625 4850);
FORCEPROP 3 LASTPIN (-5675 4850) SIG_NAME M_G_CPU0_SA_DQ<20>
J 0
(-5665 4860);
DISPLAY 0.659574 (-5665 4860);
PAINT MONO (-5665 4860);
DISPLAY INVISIBLE (-5665 4860);
FORCEPROP 1 LASTPIN (-5675 4850) BN 20
J 0
(-5687 4858);
DISPLAY 0.489362 (-5687 4858);
PAINT GREEN (-5687 4858);
FORCEPROP 2 LAST CDS_LIB mstr_standard
J 0
(-5625 4850);
DISPLAY 0.723404 (-5625 4850);
PAINT MONO (-5625 4850);
DISPLAY INVISIBLE (-5625 4850);
FORCEPROP 1 LAST BODY_TYPE PLUMBING
J 0
(-5625 4900);
DISPLAY 0.872340 (-5625 4900);
PAINT GREEN (-5625 4900);
DISPLAY INVISIBLE (-5625 4900);
FORCEPROP 1 LAST HDL_TAP TRUE
J 0
(-5300 4725);
DISPLAY 0.872340 (-5300 4725);
DISPLAY INVISIBLE (-5300 4725);
FORCEPROP 1 LAST PATH I116
J 0
(-5627 4850);
DISPLAY 0.872340 (-5627 4850);
PAINT GREEN (-5627 4850);
DISPLAY INVISIBLE (-5627 4850);
FORCEADD TAP..1
(-5625 5050);
FORCEPROP 3 LASTPIN (-5675 5050) SIG_NAME M_G_CPU0_SA_DQ<24>
J 0
(-5665 5060);
DISPLAY 0.659574 (-5665 5060);
PAINT MONO (-5665 5060);
DISPLAY INVISIBLE (-5665 5060);
FORCEPROP 1 LASTPIN (-5675 5050) BN 24
J 0
(-5687 5058);
DISPLAY 0.489362 (-5687 5058);
PAINT GREEN (-5687 5058);
FORCEPROP 2 LAST CDS_LIB mstr_standard
J 0
(-5625 5050);
DISPLAY 0.723404 (-5625 5050);
PAINT MONO (-5625 5050);
DISPLAY INVISIBLE (-5625 5050);
FORCEPROP 1 LAST BODY_TYPE PLUMBING
J 0
(-5625 5100);
DISPLAY 0.872340 (-5625 5100);
PAINT GREEN (-5625 5100);
DISPLAY INVISIBLE (-5625 5100);
FORCEPROP 1 LAST HDL_TAP TRUE
J 0
(-5300 4925);
DISPLAY 0.872340 (-5300 4925);
DISPLAY INVISIBLE (-5300 4925);
FORCEPROP 1 LAST PATH I117
J 0
(-5627 5050);
DISPLAY 0.872340 (-5627 5050);
PAINT GREEN (-5627 5050);
DISPLAY INVISIBLE (-5627 5050);
FORCEADD TAP..1
(-5625 5000);
FORCEPROP 3 LASTPIN (-5675 5000) SIG_NAME M_G_CPU0_SA_DQ<23>
J 0
(-5665 5010);
DISPLAY 0.659574 (-5665 5010);
PAINT MONO (-5665 5010);
DISPLAY INVISIBLE (-5665 5010);
FORCEPROP 1 LASTPIN (-5675 5000) BN 23
J 0
(-5687 5008);
DISPLAY 0.489362 (-5687 5008);
PAINT GREEN (-5687 5008);
FORCEPROP 2 LAST CDS_LIB mstr_standard
J 0
(-5625 5000);
DISPLAY 0.723404 (-5625 5000);
PAINT MONO (-5625 5000);
DISPLAY INVISIBLE (-5625 5000);
FORCEPROP 1 LAST BODY_TYPE PLUMBING
J 0
(-5625 5050);
DISPLAY 0.872340 (-5625 5050);
PAINT GREEN (-5625 5050);
DISPLAY INVISIBLE (-5625 5050);
FORCEPROP 1 LAST HDL_TAP TRUE
J 0
(-5300 4875);
DISPLAY 0.872340 (-5300 4875);
DISPLAY INVISIBLE (-5300 4875);
FORCEPROP 1 LAST PATH I118
J 0
(-5627 5000);
DISPLAY 0.872340 (-5627 5000);
PAINT GREEN (-5627 5000);
DISPLAY INVISIBLE (-5627 5000);
FORCEADD TAP..1
(-5625 5150);
FORCEPROP 3 LASTPIN (-5675 5150) SIG_NAME M_G_CPU0_SA_DQ<26>
J 0
(-5665 5160);
DISPLAY 0.659574 (-5665 5160);
PAINT MONO (-5665 5160);
DISPLAY INVISIBLE (-5665 5160);
FORCEPROP 1 LASTPIN (-5675 5150) BN 26
J 0
(-5687 5158);
DISPLAY 0.489362 (-5687 5158);
PAINT GREEN (-5687 5158);
FORCEPROP 2 LAST CDS_LIB mstr_standard
J 0
(-5625 5150);
DISPLAY 0.723404 (-5625 5150);
PAINT MONO (-5625 5150);
DISPLAY INVISIBLE (-5625 5150);
FORCEPROP 1 LAST BODY_TYPE PLUMBING
J 0
(-5625 5200);
DISPLAY 0.872340 (-5625 5200);
PAINT GREEN (-5625 5200);
DISPLAY INVISIBLE (-5625 5200);
FORCEPROP 1 LAST HDL_TAP TRUE
J 0
(-5300 5025);
DISPLAY 0.872340 (-5300 5025);
DISPLAY INVISIBLE (-5300 5025);
FORCEPROP 1 LAST PATH I119
J 0
(-5627 5150);
DISPLAY 0.872340 (-5627 5150);
PAINT GREEN (-5627 5150);
DISPLAY INVISIBLE (-5627 5150);
FORCEADD OFFPAGE..1
(-7925 4100);
FORCEPROP 2 LAST $XR0 16 
J 0
(-8176 4100);
DISPLAY 0.638298 (-8176 4100);
PAINT MONO (-8176 4100);
FORCEPROP 2 LAST CDS_LIB mstr_standard
J 0
(-7925 4100);
DISPLAY 0.808511 (-7925 4100);
DISPLAY INVISIBLE (-7925 4100);
FORCEPROP 1 LAST OFFPAGE TRUE
J 0
(-7600 3975);
DISPLAY 0.872340 (-7600 3975);
PAINT GREEN (-7600 3975);
DISPLAY INVISIBLE (-7600 3975);
FORCEPROP 1 LAST COMMENT_BODY TRUE
J 0
(-7800 4000);
DISPLAY 0.872340 (-7800 4000);
PAINT GREEN (-7800 4000);
DISPLAY INVISIBLE (-7800 4000);
FORCEPROP 2 LAST PATH I12
J 0
(-8175 4150);
DISPLAY 1.021277 (-8175 4150);
DISPLAY INVISIBLE (-8175 4150);
FORCEADD TAP..1
(-5625 5200);
FORCEPROP 3 LASTPIN (-5675 5200) SIG_NAME M_G_CPU0_SA_DQ<27>
J 0
(-5665 5210);
DISPLAY 0.659574 (-5665 5210);
PAINT MONO (-5665 5210);
DISPLAY INVISIBLE (-5665 5210);
FORCEPROP 1 LASTPIN (-5675 5200) BN 27
J 0
(-5687 5208);
DISPLAY 0.489362 (-5687 5208);
PAINT GREEN (-5687 5208);
FORCEPROP 2 LAST CDS_LIB mstr_standard
J 0
(-5625 5200);
DISPLAY 0.723404 (-5625 5200);
PAINT MONO (-5625 5200);
DISPLAY INVISIBLE (-5625 5200);
FORCEPROP 1 LAST BODY_TYPE PLUMBING
J 0
(-5625 5250);
DISPLAY 0.872340 (-5625 5250);
PAINT GREEN (-5625 5250);
DISPLAY INVISIBLE (-5625 5250);
FORCEPROP 1 LAST HDL_TAP TRUE
J 0
(-5300 5075);
DISPLAY 0.872340 (-5300 5075);
DISPLAY INVISIBLE (-5300 5075);
FORCEPROP 1 LAST PATH I120
J 0
(-5627 5200);
DISPLAY 0.872340 (-5627 5200);
PAINT GREEN (-5627 5200);
DISPLAY INVISIBLE (-5627 5200);
FORCEADD TAP..1
(-5625 5100);
FORCEPROP 3 LASTPIN (-5675 5100) SIG_NAME M_G_CPU0_SA_DQ<25>
J 0
(-5665 5110);
DISPLAY 0.659574 (-5665 5110);
PAINT MONO (-5665 5110);
DISPLAY INVISIBLE (-5665 5110);
FORCEPROP 1 LASTPIN (-5675 5100) BN 25
J 0
(-5687 5108);
DISPLAY 0.489362 (-5687 5108);
PAINT GREEN (-5687 5108);
FORCEPROP 2 LAST CDS_LIB mstr_standard
J 0
(-5625 5100);
DISPLAY 0.723404 (-5625 5100);
PAINT MONO (-5625 5100);
DISPLAY INVISIBLE (-5625 5100);
FORCEPROP 1 LAST BODY_TYPE PLUMBING
J 0
(-5625 5150);
DISPLAY 0.872340 (-5625 5150);
PAINT GREEN (-5625 5150);
DISPLAY INVISIBLE (-5625 5150);
FORCEPROP 1 LAST HDL_TAP TRUE
J 0
(-5300 4975);
DISPLAY 0.872340 (-5300 4975);
DISPLAY INVISIBLE (-5300 4975);
FORCEPROP 1 LAST PATH I121
J 0
(-5627 5100);
DISPLAY 0.872340 (-5627 5100);
PAINT GREEN (-5627 5100);
DISPLAY INVISIBLE (-5627 5100);
FORCEADD TAP..1
(-5625 5350);
FORCEPROP 3 LASTPIN (-5675 5350) SIG_NAME M_G_CPU0_SA_DQ<30>
J 0
(-5665 5360);
DISPLAY 0.659574 (-5665 5360);
PAINT MONO (-5665 5360);
DISPLAY INVISIBLE (-5665 5360);
FORCEPROP 1 LASTPIN (-5675 5350) BN 30
J 0
(-5687 5358);
DISPLAY 0.489362 (-5687 5358);
PAINT GREEN (-5687 5358);
FORCEPROP 2 LAST CDS_LIB mstr_standard
J 0
(-5625 5350);
DISPLAY 0.723404 (-5625 5350);
PAINT MONO (-5625 5350);
DISPLAY INVISIBLE (-5625 5350);
FORCEPROP 1 LAST BODY_TYPE PLUMBING
J 0
(-5625 5400);
DISPLAY 0.872340 (-5625 5400);
PAINT GREEN (-5625 5400);
DISPLAY INVISIBLE (-5625 5400);
FORCEPROP 1 LAST HDL_TAP TRUE
J 0
(-5300 5225);
DISPLAY 0.872340 (-5300 5225);
DISPLAY INVISIBLE (-5300 5225);
FORCEPROP 1 LAST PATH I122
J 0
(-5627 5350);
DISPLAY 0.872340 (-5627 5350);
PAINT GREEN (-5627 5350);
DISPLAY INVISIBLE (-5627 5350);
FORCEADD TAP..1
(-5625 5250);
FORCEPROP 3 LASTPIN (-5675 5250) SIG_NAME M_G_CPU0_SA_DQ<28>
J 0
(-5665 5260);
DISPLAY 0.659574 (-5665 5260);
PAINT MONO (-5665 5260);
DISPLAY INVISIBLE (-5665 5260);
FORCEPROP 1 LASTPIN (-5675 5250) BN 28
J 0
(-5687 5258);
DISPLAY 0.489362 (-5687 5258);
PAINT GREEN (-5687 5258);
FORCEPROP 2 LAST CDS_LIB mstr_standard
J 0
(-5625 5250);
DISPLAY 0.723404 (-5625 5250);
PAINT MONO (-5625 5250);
DISPLAY INVISIBLE (-5625 5250);
FORCEPROP 1 LAST BODY_TYPE PLUMBING
J 0
(-5625 5300);
DISPLAY 0.872340 (-5625 5300);
PAINT GREEN (-5625 5300);
DISPLAY INVISIBLE (-5625 5300);
FORCEPROP 1 LAST HDL_TAP TRUE
J 0
(-5300 5125);
DISPLAY 0.872340 (-5300 5125);
DISPLAY INVISIBLE (-5300 5125);
FORCEPROP 1 LAST PATH I123
J 0
(-5627 5250);
DISPLAY 0.872340 (-5627 5250);
PAINT GREEN (-5627 5250);
DISPLAY INVISIBLE (-5627 5250);
FORCEADD TAP..1
(-5625 5300);
FORCEPROP 3 LASTPIN (-5675 5300) SIG_NAME M_G_CPU0_SA_DQ<29>
J 0
(-5665 5310);
DISPLAY 0.659574 (-5665 5310);
PAINT MONO (-5665 5310);
DISPLAY INVISIBLE (-5665 5310);
FORCEPROP 1 LASTPIN (-5675 5300) BN 29
J 0
(-5687 5308);
DISPLAY 0.489362 (-5687 5308);
PAINT GREEN (-5687 5308);
FORCEPROP 2 LAST CDS_LIB mstr_standard
J 0
(-5625 5300);
DISPLAY 0.723404 (-5625 5300);
PAINT MONO (-5625 5300);
DISPLAY INVISIBLE (-5625 5300);
FORCEPROP 1 LAST BODY_TYPE PLUMBING
J 0
(-5625 5350);
DISPLAY 0.872340 (-5625 5350);
PAINT GREEN (-5625 5350);
DISPLAY INVISIBLE (-5625 5350);
FORCEPROP 1 LAST HDL_TAP TRUE
J 0
(-5300 5175);
DISPLAY 0.872340 (-5300 5175);
DISPLAY INVISIBLE (-5300 5175);
FORCEPROP 1 LAST PATH I124
J 0
(-5627 5300);
DISPLAY 0.872340 (-5627 5300);
PAINT GREEN (-5627 5300);
DISPLAY INVISIBLE (-5627 5300);
FORCEADD TAP..1
(-5625 5400);
FORCEPROP 3 LASTPIN (-5675 5400) SIG_NAME M_G_CPU0_SA_DQ<31>
J 0
(-5665 5410);
DISPLAY 0.659574 (-5665 5410);
PAINT MONO (-5665 5410);
DISPLAY INVISIBLE (-5665 5410);
FORCEPROP 1 LASTPIN (-5675 5400) BN 31
J 0
(-5687 5408);
DISPLAY 0.489362 (-5687 5408);
PAINT GREEN (-5687 5408);
FORCEPROP 2 LAST CDS_LIB mstr_standard
J 0
(-5625 5400);
DISPLAY 0.723404 (-5625 5400);
PAINT MONO (-5625 5400);
DISPLAY INVISIBLE (-5625 5400);
FORCEPROP 1 LAST BODY_TYPE PLUMBING
J 0
(-5625 5450);
DISPLAY 0.872340 (-5625 5450);
PAINT GREEN (-5625 5450);
DISPLAY INVISIBLE (-5625 5450);
FORCEPROP 1 LAST HDL_TAP TRUE
J 0
(-5300 5275);
DISPLAY 0.872340 (-5300 5275);
DISPLAY INVISIBLE (-5300 5275);
FORCEPROP 1 LAST PATH I125
J 0
(-5627 5400);
DISPLAY 0.872340 (-5627 5400);
PAINT GREEN (-5627 5400);
DISPLAY INVISIBLE (-5627 5400);
FORCEADD OFFPAGE..3
(-5025 5450);
FORCEPROP 2 LAST $XR0 16 
J 0
(-4811 5450);
DISPLAY 0.638298 (-4811 5450);
PAINT MONO (-4811 5450);
FORCEPROP 2 LAST CDS_LIB mstr_standard
J 0
(-5025 5450);
DISPLAY 0.723404 (-5025 5450);
PAINT MONO (-5025 5450);
DISPLAY INVISIBLE (-5025 5450);
FORCEPROP 1 LAST OFFPAGE TRUE
J 0
(-4700 5325);
DISPLAY 0.872340 (-4700 5325);
PAINT GREEN (-4700 5325);
DISPLAY INVISIBLE (-4700 5325);
FORCEPROP 1 LAST COMMENT_BODY TRUE
J 0
(-5075 5350);
DISPLAY 0.872340 (-5075 5350);
PAINT GREEN (-5075 5350);
DISPLAY INVISIBLE (-5075 5350);
FORCEPROP 2 LAST PATH I126
J 0
(-4700 5500);
DISPLAY 1.021277 (-4700 5500);
DISPLAY INVISIBLE (-4700 5500);
FORCEADD OFFPAGE..5
(-6800 1375);
FORCEPROP 2 LAST $XR0 92 
J 0
(-7024 1375);
DISPLAY 0.638298 (-7024 1375);
PAINT MONO (-7024 1375);
FORCEPROP 2 LAST BOM_COST MEM
J 0
(-6875 1450);
DISPLAY 0.808511 (-6875 1450);
DISPLAY INVISIBLE (-6875 1450);
FORCEPROP 2 LAST CDS_LIB mstr_standard
J 0
(-6800 1375);
DISPLAY 0.808511 (-6800 1375);
DISPLAY INVISIBLE (-6800 1375);
FORCEPROP 1 LAST OFFPAGE TRUE
J 0
(-6475 1250);
DISPLAY 0.872340 (-6475 1250);
PAINT GREEN (-6475 1250);
DISPLAY INVISIBLE (-6475 1250);
FORCEPROP 1 LAST COMMENT_BODY TRUE
J 0
(-6700 1300);
DISPLAY 0.872340 (-6700 1300);
PAINT GREEN (-6700 1300);
DISPLAY INVISIBLE (-6700 1300);
FORCEPROP 2 LAST PATH I127
J 0
(-7000 1425);
DISPLAY 1.021277 (-7000 1425);
DISPLAY INVISIBLE (-7000 1425);
FORCEADD GND..1
(-6025 975);
FORCEPROP 3 LASTPIN (-6025 1025) SIG_NAME GND\g
J 0
(-6015 1035);
DISPLAY 0.659574 (-6015 1035);
PAINT MONO (-6015 1035);
DISPLAY INVISIBLE (-6015 1035);
FORCEPROP 2 LAST BOM_COST MEM
J 0
(-6125 1050);
DISPLAY 0.808511 (-6125 1050);
DISPLAY INVISIBLE (-6125 1050);
FORCEPROP 1 LAST SIZE 1B
J 0
(-5950 925);
DISPLAY 0.851064 (-5950 925);
PAINT GREEN (-5950 925);
DISPLAY INVISIBLE (-5950 925);
FORCEPROP 2 LAST CDS_LIB mstr_symbols
J 0
(-6025 975);
DISPLAY 0.808511 (-6025 975);
DISPLAY INVISIBLE (-6025 975);
FORCEPROP 1 LAST VOLTAGE 0.0
J 0
(-6070 932);
DISPLAY 0.723404 (-6070 932);
PAINT SKYBLUE (-6070 932);
DISPLAY INVISIBLE (-6070 932);
FORCEPROP 1 LAST BODY_TYPE PLUMBING
J 0
(-6070 932);
DISPLAY 0.340426 (-6070 932);
PAINT GREEN (-6070 932);
DISPLAY INVISIBLE (-6070 932);
FORCEPROP 1 LAST HDL_POWER GND
J 0
(-6025 1125);
DISPLAY 0.851064 (-6025 1125);
PAINT GREEN (-6025 1125);
DISPLAY INVISIBLE (-6025 1125);
FORCEPROP 1 LAST PATH I128
J 0
(-5950 975);
DISPLAY 0.872340 (-5950 975);
PAINT AQUA (-5950 975);
DISPLAY INVISIBLE (-5950 975);
FORCEADD Q_RES..2
(-6025 1200);
FORCEPROP 1 LAST LOCATION R35
J 0
(-5980 1325);
DISPLAY 0.489362 (-5980 1325);
PAINT SKYBLUE (-5980 1325);
FORCEPROP 2 LAST SEC 1
J 0
(-5975 1425);
DISPLAY 0.808511 (-5975 1425);
PAINT MONO (-5975 1425);
DISPLAY INVISIBLE (-5975 1425);
FORCEPROP 1 LASTPIN (-6025 1300) $PN 1
J 0
(-6020 1262);
DISPLAY 0.489362 (-6020 1262);
PAINT WHITE (-6020 1262);
FORCEPROP 1 LASTPIN (-6025 1100) $PN 2
J 0
(-6020 1110);
DISPLAY 0.489362 (-6020 1110);
PAINT WHITE (-6020 1110);
FORCEPROP 0 LASTPIN (-6025 1300) XNET_PINS 3
R 1
J 0
(-6035 1310);
DISPLAY 0.808511 (-6035 1310);
PAINT MONO (-6035 1310);
DISPLAY INVISIBLE (-6035 1310);
FORCEPROP 0 LASTPIN (-6025 1100) XNET_PINS 2
R 1
J 2
(-6035 1090);
DISPLAY 0.808511 (-6035 1090);
PAINT MONO (-6035 1090);
DISPLAY INVISIBLE (-6035 1090);
FORCEPROP 1 LAST TOLERANCE 1%
J 0
(-5980 1225);
DISPLAY 0.489362 (-5980 1225);
PAINT SKYBLUE (-5980 1225);
FORCEPROP 1 LAST PACK_TYPE 0402LF
J 0
(-5985 1025);
DISPLAY 0.489362 (-5985 1025);
PAINT SKYBLUE (-5985 1025);
FORCEPROP 1 LAST VALUE 10K
J 0
(-5980 1275);
DISPLAY 0.489362 (-5980 1275);
PAINT SKYBLUE (-5980 1275);
FORCEPROP 1 LAST MATERIAL CHIP
J 0
(-5985 1125);
DISPLAY 0.489362 (-5985 1125);
PAINT SKYBLUE (-5985 1125);
FORCEPROP 1 LAST WATTAGE 1/16W
J 0
(-5985 1175);
DISPLAY 0.489362 (-5985 1175);
PAINT SKYBLUE (-5985 1175);
FORCEPROP 2 LAST CDS_LIB pure_quanta
J 0
(-6025 1200);
DISPLAY INVISIBLE (-6025 1200);
FORCEPROP 2 LAST BOM_COST MEM
J 0
(-5975 1375);
DISPLAY 0.808511 (-5975 1375);
DISPLAY INVISIBLE (-5975 1375);
FORCEPROP 2 LAST SEC_TYPE 0402LF
J 0
(-5975 1425);
DISPLAY 0.808511 (-5975 1425);
PAINT MONO (-5975 1425);
DISPLAY INVISIBLE (-5975 1425);
FORCEPROP 2 LAST ROOM 
J 0
(-5975 1425);
DISPLAY 0.808511 (-5975 1425);
PAINT RED (-5975 1425);
DISPLAY INVISIBLE (-5975 1425);
FORCEPROP 1 LAST PATH I129
J 0
(-5975 1375);
DISPLAY 0.978723 (-5975 1375);
PAINT WHITE (-5975 1375);
DISPLAY INVISIBLE (-5975 1375);
FORCEPROP 1 LAST PART_NUMBER CS31002FB08
J 0
(-5985 1075);
DISPLAY 0.489362 (-5985 1075);
PAINT SKYBLUE (-5985 1075);
DISPLAY INVISIBLE (-5985 1075);
FORCEADD OFFPAGE..1
(-7925 4250);
FORCEPROP 2 LAST $XR0 16 
J 0
(-8176 4250);
DISPLAY 0.638298 (-8176 4250);
PAINT MONO (-8176 4250);
FORCEPROP 2 LAST CDS_LIB mstr_standard
J 0
(-7925 4250);
DISPLAY 0.808511 (-7925 4250);
DISPLAY INVISIBLE (-7925 4250);
FORCEPROP 1 LAST OFFPAGE TRUE
J 0
(-7600 4125);
DISPLAY 0.872340 (-7600 4125);
PAINT GREEN (-7600 4125);
DISPLAY INVISIBLE (-7600 4125);
FORCEPROP 1 LAST COMMENT_BODY TRUE
J 0
(-7800 4150);
DISPLAY 0.872340 (-7800 4150);
PAINT GREEN (-7800 4150);
DISPLAY INVISIBLE (-7800 4150);
FORCEPROP 2 LAST PATH I13
J 0
(-7875 4325);
DISPLAY 1.021277 (-7875 4325);
DISPLAY INVISIBLE (-7875 4325);
FORCEADD GND..1
(-1975 1900);
FORCEPROP 3 LASTPIN (-1975 1950) SIG_NAME GND\g
J 0
(-1965 1960);
DISPLAY 0.659574 (-1965 1960);
PAINT MONO (-1965 1960);
DISPLAY INVISIBLE (-1965 1960);
FORCEPROP 2 LAST CDS_LIB mstr_symbols
J 0
(-1975 1900);
DISPLAY 0.723404 (-1975 1900);
DISPLAY INVISIBLE (-1975 1900);
FORCEPROP 1 LAST SIZE 1B
J 0
(-1900 1850);
DISPLAY 0.851064 (-1900 1850);
PAINT GREEN (-1900 1850);
DISPLAY INVISIBLE (-1900 1850);
FORCEPROP 1 LAST VOLTAGE 0.0
J 0
(-2020 1857);
DISPLAY 0.723404 (-2020 1857);
PAINT SKYBLUE (-2020 1857);
DISPLAY INVISIBLE (-2020 1857);
FORCEPROP 1 LAST BODY_TYPE PLUMBING
J 0
(-2020 1857);
DISPLAY 0.340426 (-2020 1857);
PAINT GREEN (-2020 1857);
DISPLAY INVISIBLE (-2020 1857);
FORCEPROP 1 LAST HDL_POWER GND
J 0
(-1975 2050);
DISPLAY 0.851064 (-1975 2050);
PAINT GREEN (-1975 2050);
DISPLAY INVISIBLE (-1975 2050);
FORCEPROP 1 LAST PATH I130
J 0
(-1900 1900);
DISPLAY 0.872340 (-1900 1900);
PAINT AQUA (-1900 1900);
DISPLAY INVISIBLE (-1900 1900);
FORCEADD OFFPAGE..1
(-7925 4300);
FORCEPROP 2 LAST $XR0 16 
J 0
(-8176 4300);
DISPLAY 0.638298 (-8176 4300);
PAINT MONO (-8176 4300);
FORCEPROP 2 LAST CDS_LIB mstr_standard
J 0
(-7925 4300);
DISPLAY 0.723404 (-7925 4300);
PAINT MONO (-7925 4300);
DISPLAY INVISIBLE (-7925 4300);
FORCEPROP 1 LAST OFFPAGE TRUE
J 0
(-7600 4175);
DISPLAY 0.872340 (-7600 4175);
PAINT GREEN (-7600 4175);
DISPLAY INVISIBLE (-7600 4175);
FORCEPROP 1 LAST COMMENT_BODY TRUE
J 0
(-7800 4200);
DISPLAY 0.872340 (-7800 4200);
PAINT GREEN (-7800 4200);
DISPLAY INVISIBLE (-7800 4200);
FORCEPROP 2 LAST PATH I14
J 0
(-7875 4375);
DISPLAY 1.021277 (-7875 4375);
DISPLAY INVISIBLE (-7875 4375);
FORCEADD GND..1
(-375 1700);
FORCEPROP 3 LASTPIN (-375 1750) SIG_NAME GND\g
J 0
(-365 1760);
DISPLAY 0.659574 (-365 1760);
PAINT MONO (-365 1760);
DISPLAY INVISIBLE (-365 1760);
FORCEPROP 1 LAST SIZE 1B
J 0
(-300 1650);
DISPLAY 0.851064 (-300 1650);
PAINT GREEN (-300 1650);
DISPLAY INVISIBLE (-300 1650);
FORCEPROP 2 LAST CDS_LIB mstr_symbols
J 0
(-375 1700);
DISPLAY 0.723404 (-375 1700);
DISPLAY INVISIBLE (-375 1700);
FORCEPROP 1 LAST VOLTAGE 0.0
J 0
(-420 1657);
DISPLAY 0.723404 (-420 1657);
PAINT SKYBLUE (-420 1657);
DISPLAY INVISIBLE (-420 1657);
FORCEPROP 1 LAST BODY_TYPE PLUMBING
J 0
(-420 1657);
DISPLAY 0.340426 (-420 1657);
PAINT GREEN (-420 1657);
DISPLAY INVISIBLE (-420 1657);
FORCEPROP 1 LAST HDL_POWER GND
J 0
(-375 1850);
DISPLAY 0.851064 (-375 1850);
PAINT GREEN (-375 1850);
DISPLAY INVISIBLE (-375 1850);
FORCEPROP 1 LAST PATH I146
J 0
(-300 1700);
DISPLAY 0.872340 (-300 1700);
PAINT AQUA (-300 1700);
DISPLAY INVISIBLE (-300 1700);
FORCEADD OFFPAGE..1
(-7925 4150);
FORCEPROP 2 LAST $XR0 16 
J 0
(-8176 4150);
DISPLAY 0.638298 (-8176 4150);
PAINT MONO (-8176 4150);
FORCEPROP 2 LAST CDS_LIB mstr_standard
J 0
(-7925 4150);
DISPLAY 0.723404 (-7925 4150);
PAINT MONO (-7925 4150);
DISPLAY INVISIBLE (-7925 4150);
FORCEPROP 1 LAST OFFPAGE TRUE
J 0
(-7600 4025);
DISPLAY 0.872340 (-7600 4025);
PAINT GREEN (-7600 4025);
DISPLAY INVISIBLE (-7600 4025);
FORCEPROP 1 LAST COMMENT_BODY TRUE
J 0
(-7800 4050);
DISPLAY 0.872340 (-7800 4050);
PAINT GREEN (-7800 4050);
DISPLAY INVISIBLE (-7800 4050);
FORCEPROP 2 LAST PATH I15
J 0
(-8175 4200);
DISPLAY 1.021277 (-8175 4200);
DISPLAY INVISIBLE (-8175 4200);
FORCEADD OFFPAGE..1
(-7925 4550);
FORCEPROP 2 LAST $XR0 16 
J 0
(-8176 4550);
DISPLAY 0.638298 (-8176 4550);
PAINT MONO (-8176 4550);
FORCEPROP 2 LAST CDS_LIB mstr_standard
J 0
(-7925 4550);
DISPLAY 0.808511 (-7925 4550);
DISPLAY INVISIBLE (-7925 4550);
FORCEPROP 1 LAST OFFPAGE TRUE
J 0
(-7600 4425);
DISPLAY 0.872340 (-7600 4425);
PAINT GREEN (-7600 4425);
DISPLAY INVISIBLE (-7600 4425);
FORCEPROP 1 LAST COMMENT_BODY TRUE
J 0
(-7800 4450);
DISPLAY 0.872340 (-7800 4450);
PAINT GREEN (-7800 4450);
DISPLAY INVISIBLE (-7800 4450);
FORCEPROP 2 LAST PATH I16
J 0
(-8175 4600);
DISPLAY 1.021277 (-8175 4600);
DISPLAY INVISIBLE (-8175 4600);
FORCEADD OFFPAGE..1
(-7925 4400);
FORCEPROP 2 LAST $XR0 16 
J 0
(-8176 4400);
DISPLAY 0.638298 (-8176 4400);
PAINT MONO (-8176 4400);
FORCEPROP 2 LAST CDS_LIB mstr_standard
J 0
(-7925 4400);
DISPLAY 0.808511 (-7925 4400);
DISPLAY INVISIBLE (-7925 4400);
FORCEPROP 1 LAST OFFPAGE TRUE
J 0
(-7600 4275);
DISPLAY 0.872340 (-7600 4275);
PAINT GREEN (-7600 4275);
DISPLAY INVISIBLE (-7600 4275);
FORCEPROP 1 LAST COMMENT_BODY TRUE
J 0
(-7800 4300);
DISPLAY 0.872340 (-7800 4300);
PAINT GREEN (-7800 4300);
DISPLAY INVISIBLE (-7800 4300);
FORCEPROP 2 LAST PATH I17
J 0
(-8175 4450);
DISPLAY 1.021277 (-8175 4450);
DISPLAY INVISIBLE (-8175 4450);
FORCEADD SCONN288_DDR506112002KQ..3
(-1175 3650);
FORCEPROP 1 LAST LOCATION J16
J 0
(-1625 5625);
DISPLAY 0.468085 (-1625 5625);
PAINT SKYBLUE (-1625 5625);
FORCEPROP 0 LAST $SEC 3
J 0
(-1625 5775);
DISPLAY 0.680851 (-1625 5775);
PAINT MONO (-1625 5775);
DISPLAY INVISIBLE (-1625 5775);
FORCEPROP 0 LAST CDS_SEC 3
J 0
(-1625 5775);
DISPLAY 0.680851 (-1625 5775);
DISPLAY INVISIBLE (-1625 5775);
FORCEPROP 0 LASTPIN (-575 2050) $PN G1
J 0
(-565 2060);
DISPLAY 0.680851 (-565 2060);
PAINT MONO (-565 2060);
FORCEPROP 0 LASTPIN (-575 2000) $PN G2
J 0
(-565 2010);
DISPLAY 0.680851 (-565 2010);
PAINT MONO (-565 2010);
FORCEPROP 0 LASTPIN (-575 1950) $PN G3
J 0
(-565 1960);
DISPLAY 0.680851 (-565 1960);
PAINT MONO (-565 1960);
FORCEPROP 0 LASTPIN (-1775 5200) $PN 1
J 2
(-1785 5210);
DISPLAY 0.680851 (-1785 5210);
PAINT MONO (-1785 5210);
FORCEPROP 0 LASTPIN (-1775 5250) $PN 145
J 2
(-1785 5260);
DISPLAY 0.680851 (-1785 5260);
PAINT MONO (-1785 5260);
FORCEPROP 0 LASTPIN (-1775 5300) $PN 146
J 2
(-1785 5310);
DISPLAY 0.680851 (-1785 5310);
PAINT MONO (-1785 5310);
FORCEPROP 0 LASTPIN (-575 2150) $PN 6
J 0
(-565 2160);
DISPLAY 0.680851 (-565 2160);
PAINT MONO (-565 2160);
FORCEPROP 0 LASTPIN (-575 2200) $PN 8
J 0
(-565 2210);
DISPLAY 0.680851 (-565 2210);
PAINT MONO (-565 2210);
FORCEPROP 0 LASTPIN (-575 2250) $PN 10
J 0
(-565 2260);
DISPLAY 0.680851 (-565 2260);
PAINT MONO (-565 2260);
FORCEPROP 0 LASTPIN (-575 2300) $PN 13
J 0
(-565 2310);
DISPLAY 0.680851 (-565 2310);
PAINT MONO (-565 2310);
FORCEPROP 0 LASTPIN (-575 2350) $PN 15
J 0
(-565 2360);
DISPLAY 0.680851 (-565 2360);
PAINT MONO (-565 2360);
FORCEPROP 0 LASTPIN (-575 2400) $PN 17
J 0
(-565 2410);
DISPLAY 0.680851 (-565 2410);
PAINT MONO (-565 2410);
FORCEPROP 0 LASTPIN (-575 2450) $PN 19
J 0
(-565 2460);
DISPLAY 0.680851 (-565 2460);
PAINT MONO (-565 2460);
FORCEPROP 0 LASTPIN (-575 2500) $PN 21
J 0
(-565 2510);
DISPLAY 0.680851 (-565 2510);
PAINT MONO (-565 2510);
FORCEPROP 0 LASTPIN (-575 2550) $PN 24
J 0
(-565 2560);
DISPLAY 0.680851 (-565 2560);
PAINT MONO (-565 2560);
FORCEPROP 0 LASTPIN (-575 2600) $PN 26
J 0
(-565 2610);
DISPLAY 0.680851 (-565 2610);
PAINT MONO (-565 2610);
FORCEPROP 0 LASTPIN (-575 2650) $PN 28
J 0
(-565 2660);
DISPLAY 0.680851 (-565 2660);
PAINT MONO (-565 2660);
FORCEPROP 0 LASTPIN (-575 2700) $PN 30
J 0
(-565 2710);
DISPLAY 0.680851 (-565 2710);
PAINT MONO (-565 2710);
FORCEPROP 0 LASTPIN (-575 2750) $PN 32
J 0
(-565 2760);
DISPLAY 0.680851 (-565 2760);
PAINT MONO (-565 2760);
FORCEPROP 0 LASTPIN (-575 2800) $PN 35
J 0
(-565 2810);
DISPLAY 0.680851 (-565 2810);
PAINT MONO (-565 2810);
FORCEPROP 0 LASTPIN (-575 2850) $PN 37
J 0
(-565 2860);
DISPLAY 0.680851 (-565 2860);
PAINT MONO (-565 2860);
FORCEPROP 0 LASTPIN (-575 2900) $PN 39
J 0
(-565 2910);
DISPLAY 0.680851 (-565 2910);
PAINT MONO (-565 2910);
FORCEPROP 0 LASTPIN (-575 2950) $PN 41
J 0
(-565 2960);
DISPLAY 0.680851 (-565 2960);
PAINT MONO (-565 2960);
FORCEPROP 0 LASTPIN (-575 3000) $PN 43
J 0
(-565 3010);
DISPLAY 0.680851 (-565 3010);
PAINT MONO (-565 3010);
FORCEPROP 0 LASTPIN (-575 3050) $PN 46
J 0
(-565 3060);
DISPLAY 0.680851 (-565 3060);
PAINT MONO (-565 3060);
FORCEPROP 0 LASTPIN (-575 3100) $PN 48
J 0
(-565 3110);
DISPLAY 0.680851 (-565 3110);
PAINT MONO (-565 3110);
FORCEPROP 0 LASTPIN (-575 3150) $PN 50
J 0
(-565 3160);
DISPLAY 0.680851 (-565 3160);
PAINT MONO (-565 3160);
FORCEPROP 0 LASTPIN (-575 3200) $PN 52
J 0
(-565 3210);
DISPLAY 0.680851 (-565 3210);
PAINT MONO (-565 3210);
FORCEPROP 0 LASTPIN (-575 3250) $PN 54
J 0
(-565 3260);
DISPLAY 0.680851 (-565 3260);
PAINT MONO (-565 3260);
FORCEPROP 0 LASTPIN (-575 3300) $PN 57
J 0
(-565 3310);
DISPLAY 0.680851 (-565 3310);
PAINT MONO (-565 3310);
FORCEPROP 0 LASTPIN (-575 3350) $PN 59
J 0
(-565 3360);
DISPLAY 0.680851 (-565 3360);
PAINT MONO (-565 3360);
FORCEPROP 0 LASTPIN (-575 3400) $PN 61
J 0
(-565 3410);
DISPLAY 0.680851 (-565 3410);
PAINT MONO (-565 3410);
FORCEPROP 0 LASTPIN (-575 3450) $PN 63
J 0
(-565 3460);
DISPLAY 0.680851 (-565 3460);
PAINT MONO (-565 3460);
FORCEPROP 0 LASTPIN (-575 3500) $PN 65
J 0
(-565 3510);
DISPLAY 0.680851 (-565 3510);
PAINT MONO (-565 3510);
FORCEPROP 0 LASTPIN (-575 3550) $PN 67
J 0
(-565 3560);
DISPLAY 0.680851 (-565 3560);
PAINT MONO (-565 3560);
FORCEPROP 0 LASTPIN (-575 3600) $PN 69
J 0
(-565 3610);
DISPLAY 0.680851 (-565 3610);
PAINT MONO (-565 3610);
FORCEPROP 0 LASTPIN (-575 3650) $PN 71
J 0
(-565 3660);
DISPLAY 0.680851 (-565 3660);
PAINT MONO (-565 3660);
FORCEPROP 0 LASTPIN (-575 3700) $PN 73
J 0
(-565 3710);
DISPLAY 0.680851 (-565 3710);
PAINT MONO (-565 3710);
FORCEPROP 0 LASTPIN (-575 3750) $PN 75
J 0
(-565 3760);
DISPLAY 0.680851 (-565 3760);
PAINT MONO (-565 3760);
FORCEPROP 0 LASTPIN (-575 3800) $PN 77
J 0
(-565 3810);
DISPLAY 0.680851 (-565 3810);
PAINT MONO (-565 3810);
FORCEPROP 0 LASTPIN (-575 3850) $PN 79
J 0
(-565 3860);
DISPLAY 0.680851 (-565 3860);
PAINT MONO (-565 3860);
FORCEPROP 0 LASTPIN (-575 3900) $PN 81
J 0
(-565 3910);
DISPLAY 0.680851 (-565 3910);
PAINT MONO (-565 3910);
FORCEPROP 0 LASTPIN (-575 3950) $PN 83
J 0
(-565 3960);
DISPLAY 0.680851 (-565 3960);
PAINT MONO (-565 3960);
FORCEPROP 0 LASTPIN (-575 4000) $PN 85
J 0
(-565 4010);
DISPLAY 0.680851 (-565 4010);
PAINT MONO (-565 4010);
FORCEPROP 0 LASTPIN (-575 4050) $PN 88
J 0
(-565 4060);
DISPLAY 0.680851 (-565 4060);
PAINT MONO (-565 4060);
FORCEPROP 0 LASTPIN (-575 4100) $PN 90
J 0
(-565 4110);
DISPLAY 0.680851 (-565 4110);
PAINT MONO (-565 4110);
FORCEPROP 0 LASTPIN (-575 4150) $PN 92
J 0
(-565 4160);
DISPLAY 0.680851 (-565 4160);
PAINT MONO (-565 4160);
FORCEPROP 0 LASTPIN (-575 4200) $PN 95
J 0
(-565 4210);
DISPLAY 0.680851 (-565 4210);
PAINT MONO (-565 4210);
FORCEPROP 0 LASTPIN (-575 4250) $PN 97
J 0
(-565 4260);
DISPLAY 0.680851 (-565 4260);
PAINT MONO (-565 4260);
FORCEPROP 0 LASTPIN (-575 4300) $PN 99
J 0
(-565 4310);
DISPLAY 0.680851 (-565 4310);
PAINT MONO (-565 4310);
FORCEPROP 0 LASTPIN (-575 4350) $PN 101
J 0
(-565 4360);
DISPLAY 0.680851 (-565 4360);
PAINT MONO (-565 4360);
FORCEPROP 0 LASTPIN (-575 4400) $PN 103
J 0
(-565 4410);
DISPLAY 0.680851 (-565 4410);
PAINT MONO (-565 4410);
FORCEPROP 0 LASTPIN (-575 4450) $PN 106
J 0
(-565 4460);
DISPLAY 0.680851 (-565 4460);
PAINT MONO (-565 4460);
FORCEPROP 0 LASTPIN (-575 4500) $PN 108
J 0
(-565 4510);
DISPLAY 0.680851 (-565 4510);
PAINT MONO (-565 4510);
FORCEPROP 0 LASTPIN (-575 4550) $PN 110
J 0
(-565 4560);
DISPLAY 0.680851 (-565 4560);
PAINT MONO (-565 4560);
FORCEPROP 0 LASTPIN (-575 4600) $PN 112
J 0
(-565 4610);
DISPLAY 0.680851 (-565 4610);
PAINT MONO (-565 4610);
FORCEPROP 0 LASTPIN (-575 4650) $PN 114
J 0
(-565 4660);
DISPLAY 0.680851 (-565 4660);
PAINT MONO (-565 4660);
FORCEPROP 0 LASTPIN (-575 4700) $PN 117
J 0
(-565 4710);
DISPLAY 0.680851 (-565 4710);
PAINT MONO (-565 4710);
FORCEPROP 0 LASTPIN (-575 4750) $PN 119
J 0
(-565 4760);
DISPLAY 0.680851 (-565 4760);
PAINT MONO (-565 4760);
FORCEPROP 0 LASTPIN (-575 4800) $PN 121
J 0
(-565 4810);
DISPLAY 0.680851 (-565 4810);
PAINT MONO (-565 4810);
FORCEPROP 0 LASTPIN (-575 4850) $PN 123
J 0
(-565 4860);
DISPLAY 0.680851 (-565 4860);
PAINT MONO (-565 4860);
FORCEPROP 0 LASTPIN (-575 4900) $PN 125
J 0
(-565 4910);
DISPLAY 0.680851 (-565 4910);
PAINT MONO (-565 4910);
FORCEPROP 0 LASTPIN (-575 4950) $PN 128
J 0
(-565 4960);
DISPLAY 0.680851 (-565 4960);
PAINT MONO (-565 4960);
FORCEPROP 0 LASTPIN (-575 5000) $PN 130
J 0
(-565 5010);
DISPLAY 0.680851 (-565 5010);
PAINT MONO (-565 5010);
FORCEPROP 0 LASTPIN (-575 5050) $PN 132
J 0
(-565 5060);
DISPLAY 0.680851 (-565 5060);
PAINT MONO (-565 5060);
FORCEPROP 0 LASTPIN (-575 5100) $PN 134
J 0
(-565 5110);
DISPLAY 0.680851 (-565 5110);
PAINT MONO (-565 5110);
FORCEPROP 0 LASTPIN (-575 5150) $PN 136
J 0
(-565 5160);
DISPLAY 0.680851 (-565 5160);
PAINT MONO (-565 5160);
FORCEPROP 0 LASTPIN (-575 5200) $PN 139
J 0
(-565 5210);
DISPLAY 0.680851 (-565 5210);
PAINT MONO (-565 5210);
FORCEPROP 0 LASTPIN (-575 5250) $PN 141
J 0
(-565 5260);
DISPLAY 0.680851 (-565 5260);
PAINT MONO (-565 5260);
FORCEPROP 0 LASTPIN (-575 5300) $PN 143
J 0
(-565 5310);
DISPLAY 0.680851 (-565 5310);
PAINT MONO (-565 5310);
FORCEPROP 0 LASTPIN (-1775 2050) $PN 151
J 2
(-1785 2060);
DISPLAY 0.680851 (-1785 2060);
PAINT MONO (-1785 2060);
FORCEPROP 0 LASTPIN (-1775 2100) $PN 153
J 2
(-1785 2110);
DISPLAY 0.680851 (-1785 2110);
PAINT MONO (-1785 2110);
FORCEPROP 0 LASTPIN (-1775 2150) $PN 155
J 2
(-1785 2160);
DISPLAY 0.680851 (-1785 2160);
PAINT MONO (-1785 2160);
FORCEPROP 0 LASTPIN (-1775 2200) $PN 158
J 2
(-1785 2210);
DISPLAY 0.680851 (-1785 2210);
PAINT MONO (-1785 2210);
FORCEPROP 0 LASTPIN (-1775 2250) $PN 160
J 2
(-1785 2260);
DISPLAY 0.680851 (-1785 2260);
PAINT MONO (-1785 2260);
FORCEPROP 0 LASTPIN (-1775 2300) $PN 162
J 2
(-1785 2310);
DISPLAY 0.680851 (-1785 2310);
PAINT MONO (-1785 2310);
FORCEPROP 0 LASTPIN (-1775 2350) $PN 164
J 2
(-1785 2360);
DISPLAY 0.680851 (-1785 2360);
PAINT MONO (-1785 2360);
FORCEPROP 0 LASTPIN (-1775 2400) $PN 166
J 2
(-1785 2410);
DISPLAY 0.680851 (-1785 2410);
PAINT MONO (-1785 2410);
FORCEPROP 0 LASTPIN (-1775 2450) $PN 169
J 2
(-1785 2460);
DISPLAY 0.680851 (-1785 2460);
PAINT MONO (-1785 2460);
FORCEPROP 0 LASTPIN (-1775 2500) $PN 171
J 2
(-1785 2510);
DISPLAY 0.680851 (-1785 2510);
PAINT MONO (-1785 2510);
FORCEPROP 0 LASTPIN (-1775 2550) $PN 173
J 2
(-1785 2560);
DISPLAY 0.680851 (-1785 2560);
PAINT MONO (-1785 2560);
FORCEPROP 0 LASTPIN (-1775 2600) $PN 175
J 2
(-1785 2610);
DISPLAY 0.680851 (-1785 2610);
PAINT MONO (-1785 2610);
FORCEPROP 0 LASTPIN (-1775 2650) $PN 177
J 2
(-1785 2660);
DISPLAY 0.680851 (-1785 2660);
PAINT MONO (-1785 2660);
FORCEPROP 0 LASTPIN (-1775 2700) $PN 180
J 2
(-1785 2710);
DISPLAY 0.680851 (-1785 2710);
PAINT MONO (-1785 2710);
FORCEPROP 0 LASTPIN (-1775 2750) $PN 182
J 2
(-1785 2760);
DISPLAY 0.680851 (-1785 2760);
PAINT MONO (-1785 2760);
FORCEPROP 0 LASTPIN (-1775 2800) $PN 184
J 2
(-1785 2810);
DISPLAY 0.680851 (-1785 2810);
PAINT MONO (-1785 2810);
FORCEPROP 0 LASTPIN (-1775 2850) $PN 186
J 2
(-1785 2860);
DISPLAY 0.680851 (-1785 2860);
PAINT MONO (-1785 2860);
FORCEPROP 0 LASTPIN (-1775 2900) $PN 188
J 2
(-1785 2910);
DISPLAY 0.680851 (-1785 2910);
PAINT MONO (-1785 2910);
FORCEPROP 0 LASTPIN (-1775 2950) $PN 191
J 2
(-1785 2960);
DISPLAY 0.680851 (-1785 2960);
PAINT MONO (-1785 2960);
FORCEPROP 0 LASTPIN (-1775 3000) $PN 193
J 2
(-1785 3010);
DISPLAY 0.680851 (-1785 3010);
PAINT MONO (-1785 3010);
FORCEPROP 0 LASTPIN (-1775 3050) $PN 195
J 2
(-1785 3060);
DISPLAY 0.680851 (-1785 3060);
PAINT MONO (-1785 3060);
FORCEPROP 0 LASTPIN (-1775 3100) $PN 197
J 2
(-1785 3110);
DISPLAY 0.680851 (-1785 3110);
PAINT MONO (-1785 3110);
FORCEPROP 0 LASTPIN (-1775 3150) $PN 199
J 2
(-1785 3160);
DISPLAY 0.680851 (-1785 3160);
PAINT MONO (-1785 3160);
FORCEPROP 0 LASTPIN (-1775 3200) $PN 202
J 2
(-1785 3210);
DISPLAY 0.680851 (-1785 3210);
PAINT MONO (-1785 3210);
FORCEPROP 0 LASTPIN (-1775 3250) $PN 204
J 2
(-1785 3260);
DISPLAY 0.680851 (-1785 3260);
PAINT MONO (-1785 3260);
FORCEPROP 0 LASTPIN (-1775 3300) $PN 206
J 2
(-1785 3310);
DISPLAY 0.680851 (-1785 3310);
PAINT MONO (-1785 3310);
FORCEPROP 0 LASTPIN (-1775 3350) $PN 208
J 2
(-1785 3360);
DISPLAY 0.680851 (-1785 3360);
PAINT MONO (-1785 3360);
FORCEPROP 0 LASTPIN (-1775 3400) $PN 210
J 2
(-1785 3410);
DISPLAY 0.680851 (-1785 3410);
PAINT MONO (-1785 3410);
FORCEPROP 0 LASTPIN (-1775 3450) $PN 212
J 2
(-1785 3460);
DISPLAY 0.680851 (-1785 3460);
PAINT MONO (-1785 3460);
FORCEPROP 0 LASTPIN (-1775 3500) $PN 214
J 2
(-1785 3510);
DISPLAY 0.680851 (-1785 3510);
PAINT MONO (-1785 3510);
FORCEPROP 0 LASTPIN (-1775 3550) $PN 216
J 2
(-1785 3560);
DISPLAY 0.680851 (-1785 3560);
PAINT MONO (-1785 3560);
FORCEPROP 0 LASTPIN (-1775 3600) $PN 219
J 2
(-1785 3610);
DISPLAY 0.680851 (-1785 3610);
PAINT MONO (-1785 3610);
FORCEPROP 0 LASTPIN (-1775 3650) $PN 222
J 2
(-1785 3660);
DISPLAY 0.680851 (-1785 3660);
PAINT MONO (-1785 3660);
FORCEPROP 0 LASTPIN (-1775 3700) $PN 224
J 2
(-1785 3710);
DISPLAY 0.680851 (-1785 3710);
PAINT MONO (-1785 3710);
FORCEPROP 0 LASTPIN (-1775 3750) $PN 226
J 2
(-1785 3760);
DISPLAY 0.680851 (-1785 3760);
PAINT MONO (-1785 3760);
FORCEPROP 0 LASTPIN (-1775 3800) $PN 228
J 2
(-1785 3810);
DISPLAY 0.680851 (-1785 3810);
PAINT MONO (-1785 3810);
FORCEPROP 0 LASTPIN (-1775 3850) $PN 230
J 2
(-1785 3860);
DISPLAY 0.680851 (-1785 3860);
PAINT MONO (-1785 3860);
FORCEPROP 0 LASTPIN (-1775 3900) $PN 233
J 2
(-1785 3910);
DISPLAY 0.680851 (-1785 3910);
PAINT MONO (-1785 3910);
FORCEPROP 0 LASTPIN (-1775 3950) $PN 235
J 2
(-1785 3960);
DISPLAY 0.680851 (-1785 3960);
PAINT MONO (-1785 3960);
FORCEPROP 0 LASTPIN (-1775 4000) $PN 237
J 2
(-1785 4010);
DISPLAY 0.680851 (-1785 4010);
PAINT MONO (-1785 4010);
FORCEPROP 0 LASTPIN (-1775 4050) $PN 240
J 2
(-1785 4060);
DISPLAY 0.680851 (-1785 4060);
PAINT MONO (-1785 4060);
FORCEPROP 0 LASTPIN (-1775 4100) $PN 242
J 2
(-1785 4110);
DISPLAY 0.680851 (-1785 4110);
PAINT MONO (-1785 4110);
FORCEPROP 0 LASTPIN (-1775 4150) $PN 244
J 2
(-1785 4160);
DISPLAY 0.680851 (-1785 4160);
PAINT MONO (-1785 4160);
FORCEPROP 0 LASTPIN (-1775 4200) $PN 246
J 2
(-1785 4210);
DISPLAY 0.680851 (-1785 4210);
PAINT MONO (-1785 4210);
FORCEPROP 0 LASTPIN (-1775 4250) $PN 248
J 2
(-1785 4260);
DISPLAY 0.680851 (-1785 4260);
PAINT MONO (-1785 4260);
FORCEPROP 0 LASTPIN (-1775 4300) $PN 251
J 2
(-1785 4310);
DISPLAY 0.680851 (-1785 4310);
PAINT MONO (-1785 4310);
FORCEPROP 0 LASTPIN (-1775 4350) $PN 253
J 2
(-1785 4360);
DISPLAY 0.680851 (-1785 4360);
PAINT MONO (-1785 4360);
FORCEPROP 0 LASTPIN (-1775 4400) $PN 255
J 2
(-1785 4410);
DISPLAY 0.680851 (-1785 4410);
PAINT MONO (-1785 4410);
FORCEPROP 0 LASTPIN (-1775 4450) $PN 257
J 2
(-1785 4460);
DISPLAY 0.680851 (-1785 4460);
PAINT MONO (-1785 4460);
FORCEPROP 0 LASTPIN (-1775 4500) $PN 259
J 2
(-1785 4510);
DISPLAY 0.680851 (-1785 4510);
PAINT MONO (-1785 4510);
FORCEPROP 0 LASTPIN (-1775 4550) $PN 262
J 2
(-1785 4560);
DISPLAY 0.680851 (-1785 4560);
PAINT MONO (-1785 4560);
FORCEPROP 0 LASTPIN (-1775 4600) $PN 264
J 2
(-1785 4610);
DISPLAY 0.680851 (-1785 4610);
PAINT MONO (-1785 4610);
FORCEPROP 0 LASTPIN (-1775 4650) $PN 266
J 2
(-1785 4660);
DISPLAY 0.680851 (-1785 4660);
PAINT MONO (-1785 4660);
FORCEPROP 0 LASTPIN (-1775 4700) $PN 268
J 2
(-1785 4710);
DISPLAY 0.680851 (-1785 4710);
PAINT MONO (-1785 4710);
FORCEPROP 0 LASTPIN (-1775 4750) $PN 270
J 2
(-1785 4760);
DISPLAY 0.680851 (-1785 4760);
PAINT MONO (-1785 4760);
FORCEPROP 0 LASTPIN (-1775 4800) $PN 273
J 2
(-1785 4810);
DISPLAY 0.680851 (-1785 4810);
PAINT MONO (-1785 4810);
FORCEPROP 0 LASTPIN (-1775 4850) $PN 275
J 2
(-1785 4860);
DISPLAY 0.680851 (-1785 4860);
PAINT MONO (-1785 4860);
FORCEPROP 0 LASTPIN (-1775 4900) $PN 277
J 2
(-1785 4910);
DISPLAY 0.680851 (-1785 4910);
PAINT MONO (-1785 4910);
FORCEPROP 0 LASTPIN (-1775 4950) $PN 279
J 2
(-1785 4960);
DISPLAY 0.680851 (-1785 4960);
PAINT MONO (-1785 4960);
FORCEPROP 0 LASTPIN (-1775 5000) $PN 281
J 2
(-1785 5010);
DISPLAY 0.680851 (-1785 5010);
PAINT MONO (-1785 5010);
FORCEPROP 0 LASTPIN (-1775 5050) $PN 284
J 2
(-1785 5060);
DISPLAY 0.680851 (-1785 5060);
PAINT MONO (-1785 5060);
FORCEPROP 0 LASTPIN (-1775 5100) $PN 286
J 2
(-1785 5110);
DISPLAY 0.680851 (-1785 5110);
PAINT MONO (-1785 5110);
FORCEPROP 0 LASTPIN (-1775 5150) $PN 288
J 2
(-1785 5160);
DISPLAY 0.680851 (-1785 5160);
PAINT MONO (-1785 5160);
FORCEPROP 2 LAST VALUE SCONN288_DDR506112002KQ
J 0
(-1625 5675);
DISPLAY 0.489362 (-1625 5675);
PAINT SKYBLUE (-1625 5675);
FORCEPROP 2 LAST PART_TYPE SMLF
J 0
(-1625 5725);
DISPLAY 1.021277 (-1625 5725);
FORCEPROP 1 LAST MATERIAL IO
J 0
(-1625 5475);
DISPLAY 0.468085 (-1625 5475);
PAINT SKYBLUE (-1625 5475);
FORCEPROP 1 LAST CDS_LMAN_SYM_OUTLINE -450,1800,450,-1750
J 0
(-1175 3650);
DISPLAY 0.468085 (-1175 3650);
PAINT GREEN (-1175 3650);
DISPLAY INVISIBLE (-1175 3650);
FORCEPROP 1 LAST NEEDS_NO_SIZE TRUE
J 0
(-1175 3650);
DISPLAY 0.723404 (-1175 3650);
PAINT GREEN (-1175 3650);
DISPLAY INVISIBLE (-1175 3650);
FORCEPROP 2 LAST CDS_LIB pure_quanta
J 0
(-1175 3650);
DISPLAY INVISIBLE (-1175 3650);
FORCEPROP 1 LAST PATH I177
J 0
(-1175 3650);
DISPLAY 0.723404 (-1175 3650);
PAINT GREEN (-1175 3650);
DISPLAY INVISIBLE (-1175 3650);
FORCEPROP 1 LAST PART_NUMBER DFHST8FS479
J 0
(-1625 5550);
DISPLAY 0.468085 (-1625 5550);
PAINT SKYBLUE (-1625 5550);
DISPLAY INVISIBLE (-1625 5550);
FORCEADD OFFPAGE..1
(-7925 4450);
FORCEPROP 2 LAST $XR0 16 
J 0
(-8176 4450);
DISPLAY 0.638298 (-8176 4450);
PAINT MONO (-8176 4450);
FORCEPROP 2 LAST CDS_LIB mstr_standard
J 0
(-7925 4450);
DISPLAY 0.723404 (-7925 4450);
PAINT MONO (-7925 4450);
DISPLAY INVISIBLE (-7925 4450);
FORCEPROP 1 LAST OFFPAGE TRUE
J 0
(-7600 4325);
DISPLAY 0.872340 (-7600 4325);
PAINT GREEN (-7600 4325);
DISPLAY INVISIBLE (-7600 4325);
FORCEPROP 1 LAST COMMENT_BODY TRUE
J 0
(-7800 4350);
DISPLAY 0.872340 (-7800 4350);
PAINT GREEN (-7800 4350);
DISPLAY INVISIBLE (-7800 4350);
FORCEPROP 2 LAST PATH I18
J 0
(-8175 4500);
DISPLAY 1.021277 (-8175 4500);
DISPLAY INVISIBLE (-8175 4500);
FORCEADD Q_CAP..1
R 2
(-8500 3225);
FORCEPROP 1 LAST LOCATION C112
J 2
(-8550 3325);
DISPLAY 0.489362 (-8550 3325);
PAINT SKYBLUE (-8550 3325);
FORCEPROP 0 LAST $SEC 1
J 0
(-8550 3375);
DISPLAY 0.680851 (-8550 3375);
PAINT MONO (-8550 3375);
DISPLAY INVISIBLE (-8550 3375);
FORCEPROP 0 LAST CDS_SEC 1
J 0
(-8550 3375);
DISPLAY 1.021277 (-8550 3375);
DISPLAY INVISIBLE (-8550 3375);
FORCEPROP 1 LASTPIN (-8500 3325) $PN 1
J 2
(-8510 3305);
DISPLAY 0.489362 (-8510 3305);
PAINT MONO (-8510 3305);
FORCEPROP 1 LASTPIN (-8500 3125) $PN 2
J 2
(-8510 3105);
DISPLAY 0.489362 (-8510 3105);
PAINT MONO (-8510 3105);
FORCEPROP 1 LAST VOLTAGE 25V
J 2
(-8550 3225);
DISPLAY 0.489362 (-8550 3225);
PAINT SKYBLUE (-8550 3225);
FORCEPROP 1 LAST VALUE 0.1UF
J 2
(-8550 3275);
DISPLAY 0.489362 (-8550 3275);
PAINT SKYBLUE (-8550 3275);
FORCEPROP 1 LAST MATERIAL X7R
J 2
(-8550 3125);
DISPLAY 0.489362 (-8550 3125);
PAINT SKYBLUE (-8550 3125);
FORCEPROP 1 LAST TOLERANCE 10%
J 2
(-8550 3175);
DISPLAY 0.489362 (-8550 3175);
PAINT SKYBLUE (-8550 3175);
FORCEPROP 1 LAST PACK_TYPE 0402
J 2
(-8550 3025);
DISPLAY 0.489362 (-8550 3025);
PAINT SKYBLUE (-8550 3025);
FORCEPROP 0 LAST BOM_COST MEM
J 2
(-8555 3370);
DISPLAY 0.595745 (-8555 3370);
PAINT MONO (-8555 3370);
DISPLAY INVISIBLE (-8555 3370);
FORCEPROP 2 LAST CDS_LIB pure_quanta
J 0
(-8500 3225);
DISPLAY INVISIBLE (-8500 3225);
FORCEPROP 2 LAST ROOM 
J 2
(-8555 3370);
DISPLAY 0.595745 (-8555 3370);
PAINT RED (-8555 3370);
DISPLAY INVISIBLE (-8555 3370);
FORCEPROP 1 LAST PATH I183
J 2
(-8550 3375);
DISPLAY 0.978723 (-8550 3375);
PAINT WHITE (-8550 3375);
DISPLAY INVISIBLE (-8550 3375);
FORCEPROP 1 LAST PART_NUMBER CH4104K1B00
J 2
(-8550 3075);
DISPLAY 0.489362 (-8550 3075);
PAINT SKYBLUE (-8550 3075);
DISPLAY INVISIBLE (-8550 3075);
FORCEADD GND..1
(-8500 3000);
FORCEPROP 3 LASTPIN (-8500 3050) SIG_NAME GND\g
J 0
(-8490 3060);
DISPLAY 0.659574 (-8490 3060);
PAINT MONO (-8490 3060);
DISPLAY INVISIBLE (-8490 3060);
FORCEPROP 2 LAST CDS_LIB mstr_symbols
J 0
(-8500 3000);
DISPLAY 0.808511 (-8500 3000);
DISPLAY INVISIBLE (-8500 3000);
FORCEPROP 1 LAST SIZE 1B
J 0
(-8425 2950);
DISPLAY 0.723404 (-8425 2950);
PAINT GREEN (-8425 2950);
DISPLAY INVISIBLE (-8425 2950);
FORCEPROP 2 LAST BOM_COST MEM
J 0
(-8475 3125);
DISPLAY 0.659574 (-8475 3125);
DISPLAY INVISIBLE (-8475 3125);
FORCEPROP 1 LAST VOLTAGE 0
J 0
(-8520 3095);
DISPLAY 0.829787 (-8520 3095);
PAINT SKYBLUE (-8520 3095);
DISPLAY INVISIBLE (-8520 3095);
FORCEPROP 2 LAST ROOM MEM_EFGH_DECOUPLING_CAPS
J 0
(-8475 3075);
DISPLAY 0.659574 (-8475 3075);
PAINT RED (-8475 3075);
DISPLAY INVISIBLE (-8475 3075);
FORCEPROP 1 LAST BODY_TYPE PLUMBING
J 0
(-8545 2957);
DISPLAY 0.276596 (-8545 2957);
PAINT GREEN (-8545 2957);
DISPLAY INVISIBLE (-8545 2957);
FORCEPROP 1 LAST HDL_POWER GND
J 0
(-8500 3150);
DISPLAY 0.723404 (-8500 3150);
PAINT GREEN (-8500 3150);
DISPLAY INVISIBLE (-8500 3150);
FORCEPROP 1 LAST PATH I184
J 0
(-8425 3000);
DISPLAY 0.872340 (-8425 3000);
PAINT AQUA (-8425 3000);
DISPLAY INVISIBLE (-8425 3000);
FORCEADD OFFPAGE..6
(-8900 2150);
FORCEPROP 2 LAST $XR5 97 
J 0
(-9329 2114);
DISPLAY 0.638298 (-9329 2114);
PAINT MONO (-9329 2114);
FORCEPROP 2 LAST $XR4 96 
J 0
(-9239 2114);
DISPLAY 0.638298 (-9239 2114);
PAINT MONO (-9239 2114);
FORCEPROP 2 LAST $XR3 95 
J 0
(-9149 2114);
DISPLAY 0.638298 (-9149 2114);
PAINT MONO (-9149 2114);
FORCEPROP 2 LAST $XR2 94 
J 0
(-9329 2150);
DISPLAY 0.638298 (-9329 2150);
PAINT MONO (-9329 2150);
FORCEPROP 2 LAST $XR1 93 
J 0
(-9239 2150);
DISPLAY 0.638298 (-9239 2150);
PAINT MONO (-9239 2150);
FORCEPROP 2 LAST $XR0 92 
J 0
(-9149 2150);
DISPLAY 0.638298 (-9149 2150);
PAINT MONO (-9149 2150);
FORCEPROP 2 LAST CDS_LIB mstr_standard
J 0
(-8900 2150);
DISPLAY INVISIBLE (-8900 2150);
FORCEPROP 1 LAST OFFPAGE TRUE
J 0
(-8575 2025);
DISPLAY 0.872340 (-8575 2025);
PAINT GREEN (-8575 2025);
DISPLAY INVISIBLE (-8575 2025);
FORCEPROP 1 LAST COMMENT_BODY TRUE
J 0
(-8800 2075);
DISPLAY 0.872340 (-8800 2075);
PAINT GREEN (-8800 2075);
DISPLAY INVISIBLE (-8800 2075);
FORCEPROP 2 LAST PATH I185
J 0
(-8850 2225);
DISPLAY 1.021277 (-8850 2225);
DISPLAY INVISIBLE (-8850 2225);
FORCEADD Q_RES..1
R 2
(-8350 2150);
FORCEPROP 1 LAST LOCATION R297
J 2
(-8300 2200);
DISPLAY 0.489362 (-8300 2200);
PAINT SKYBLUE (-8300 2200);
FORCEPROP 0 LAST $SEC 1
J 0
(-8300 2250);
DISPLAY 0.680851 (-8300 2250);
PAINT MONO (-8300 2250);
DISPLAY INVISIBLE (-8300 2250);
FORCEPROP 0 LAST CDS_SEC 1
J 0
(-8300 2250);
DISPLAY 1.021277 (-8300 2250);
DISPLAY INVISIBLE (-8300 2250);
FORCEPROP 1 LASTPIN (-8250 2150) $PN 1
J 2
(-8262 2162);
DISPLAY 0.489362 (-8262 2162);
PAINT MONO (-8262 2162);
FORCEPROP 1 LASTPIN (-8450 2150) $PN 2
J 2
(-8412 2162);
DISPLAY 0.489362 (-8412 2162);
PAINT MONO (-8412 2162);
FORCEPROP 1 LAST VALUE 1K
J 0
(-8350 2100);
DISPLAY 0.489362 (-8350 2100);
PAINT SKYBLUE (-8350 2100);
FORCEPROP 1 LAST TOLERANCE 1%
J 2
(-8225 2125);
DISPLAY 0.489362 (-8225 2125);
PAINT SKYBLUE (-8225 2125);
DISPLAY INVISIBLE (-8225 2125);
FORCEPROP 2 LAST CDS_LIB pure_quanta
J 0
(-8350 2150);
DISPLAY INVISIBLE (-8350 2150);
FORCEPROP 2 LAST BOM_COST MEM
J 0
(-8375 2300);
DISPLAY 0.744681 (-8375 2300);
PAINT WHITE (-8375 2300);
DISPLAY INVISIBLE (-8375 2300);
FORCEPROP 1 LAST WATTAGE 1/16W
J 0
(-8275 2075);
DISPLAY 0.489362 (-8275 2075);
PAINT SKYBLUE (-8275 2075);
DISPLAY INVISIBLE (-8275 2075);
FORCEPROP 1 LAST MATERIAL CHIP
J 0
(-8525 2125);
DISPLAY 0.489362 (-8525 2125);
PAINT SKYBLUE (-8525 2125);
DISPLAY INVISIBLE (-8525 2125);
FORCEPROP 1 LAST PACK_TYPE 0402LF
J 0
(-8525 2075);
DISPLAY 0.489362 (-8525 2075);
PAINT SKYBLUE (-8525 2075);
DISPLAY INVISIBLE (-8525 2075);
FORCEPROP 2 LAST ROOM 
J 0
(-8375 2250);
DISPLAY 0.744681 (-8375 2250);
PAINT RED (-8375 2250);
DISPLAY INVISIBLE (-8375 2250);
FORCEPROP 1 LAST PATH I186
J 2
(-8300 2300);
DISPLAY 0.978723 (-8300 2300);
PAINT WHITE (-8300 2300);
DISPLAY INVISIBLE (-8300 2300);
FORCEPROP 1 LAST PART_NUMBER CS21002FB06
J 0
(-8450 2200);
DISPLAY 0.489362 (-8450 2200);
PAINT SKYBLUE (-8450 2200);
DISPLAY INVISIBLE (-8450 2200);
FORCEADD Q_RES..2
(-8225 2300);
FORCEPROP 1 LAST LOCATION R96
J 0
(-8180 2425);
DISPLAY 0.489362 (-8180 2425);
PAINT SKYBLUE (-8180 2425);
FORCEPROP 0 LAST $SEC 1
J 0
(-8175 2475);
DISPLAY 0.680851 (-8175 2475);
PAINT MONO (-8175 2475);
DISPLAY INVISIBLE (-8175 2475);
FORCEPROP 0 LAST CDS_SEC 1
J 0
(-8175 2475);
DISPLAY 1.021277 (-8175 2475);
DISPLAY INVISIBLE (-8175 2475);
FORCEPROP 1 LASTPIN (-8225 2400) $PN 1
J 0
(-8220 2362);
DISPLAY 0.489362 (-8220 2362);
PAINT MONO (-8220 2362);
FORCEPROP 1 LASTPIN (-8225 2200) $PN 2
J 0
(-8220 2210);
DISPLAY 0.489362 (-8220 2210);
PAINT MONO (-8220 2210);
FORCEPROP 1 LAST TOLERANCE 1%
J 0
(-8175 2350);
DISPLAY 0.489362 (-8175 2350);
PAINT SKYBLUE (-8175 2350);
FORCEPROP 1 LAST WATTAGE 1/16W
J 0
(-8175 2325);
DISPLAY 0.489362 (-8175 2325);
PAINT SKYBLUE (-8175 2325);
FORCEPROP 1 LAST MATERIAL EMPTY
J 0
(-8175 2300);
DISPLAY 0.489362 (-8175 2300);
PAINT RED (-8175 2300);
FORCEPROP 1 LAST VALUE 1K
J 0
(-8180 2375);
DISPLAY 0.489362 (-8180 2375);
PAINT SKYBLUE (-8180 2375);
FORCEPROP 1 LAST PACK_TYPE 0402LF
J 0
(-8175 2250);
DISPLAY 0.489362 (-8175 2250);
PAINT SKYBLUE (-8175 2250);
FORCEPROP 2 LAST CDS_LIB pure_quanta
J 0
(-8225 2300);
DISPLAY INVISIBLE (-8225 2300);
FORCEPROP 2 LAST BOM_COST MEM
J 0
(-8175 2475);
DISPLAY 0.808511 (-8175 2475);
DISPLAY INVISIBLE (-8175 2475);
FORCEPROP 2 LAST ROOM 
J 0
(-8175 2525);
DISPLAY 0.808511 (-8175 2525);
PAINT RED (-8175 2525);
DISPLAY INVISIBLE (-8175 2525);
FORCEPROP 1 LAST PATH I187
J 0
(-8175 2475);
DISPLAY 0.978723 (-8175 2475);
PAINT WHITE (-8175 2475);
DISPLAY INVISIBLE (-8175 2475);
FORCEPROP 1 LAST PART_NUMBER CS21002FB06
J 0
(-8175 2275);
DISPLAY 0.489362 (-8175 2275);
PAINT SKYBLUE (-8175 2275);
DISPLAY INVISIBLE (-8175 2275);
FORCEADD VCC_CORE..1
(-8225 2475);
FORCEPROP 3 LASTPIN (-8225 2425) SIG_NAME P3V3\g
J 0
(-8215 2435);
DISPLAY 0.659574 (-8215 2435);
PAINT MONO (-8215 2435);
DISPLAY INVISIBLE (-8215 2435);
FORCEPROP 1 LAST HDL_POWER P3V3
J 1
(-8225 2525);
DISPLAY 0.489362 (-8225 2525);
PAINT GREEN (-8225 2525);
FORCEPROP 2 LAST CDS_LIB mstr_symbols
J 0
(-8225 2475);
DISPLAY INVISIBLE (-8225 2475);
FORCEPROP 0 LAST VOLTAGE 3.3
J 0
(-8500 2625);
DISPLAY 1.021277 (-8500 2625);
PAINT SKYBLUE (-8500 2625);
DISPLAY INVISIBLE (-8500 2625);
FORCEPROP 2 LAST ROOM PVCCINFAON_CPU0_CTRL
J 0
(-8225 2575);
DISPLAY 0.808511 (-8225 2575);
PAINT RED (-8225 2575);
DISPLAY INVISIBLE (-8225 2575);
FORCEPROP 1 LAST PATH I188
J 0
(-8175 2500);
DISPLAY 0.872340 (-8175 2500);
PAINT AQUA (-8175 2500);
DISPLAY INVISIBLE (-8175 2500);
FORCEADD VCC_CORE..1
(-8475 2475);
FORCEPROP 3 LASTPIN (-8475 2425) SIG_NAME P3V3\g
J 0
(-8465 2435);
DISPLAY 0.659574 (-8465 2435);
PAINT MONO (-8465 2435);
DISPLAY INVISIBLE (-8465 2435);
FORCEPROP 1 LAST HDL_POWER P3V3
J 1
(-8475 2525);
DISPLAY 0.489362 (-8475 2525);
PAINT GREEN (-8475 2525);
FORCEPROP 2 LAST CDS_LIB mstr_symbols
J 0
(-8475 2475);
DISPLAY INVISIBLE (-8475 2475);
FORCEPROP 0 LAST VOLTAGE 3.3
J 0
(-8750 2625);
DISPLAY 1.021277 (-8750 2625);
PAINT SKYBLUE (-8750 2625);
DISPLAY INVISIBLE (-8750 2625);
FORCEPROP 2 LAST ROOM PVCCINFAON_CPU0_CTRL
J 0
(-8475 2575);
DISPLAY 0.808511 (-8475 2575);
PAINT RED (-8475 2575);
DISPLAY INVISIBLE (-8475 2575);
FORCEPROP 1 LAST PATH I189
J 0
(-8425 2500);
DISPLAY 0.872340 (-8425 2500);
PAINT AQUA (-8425 2500);
DISPLAY INVISIBLE (-8425 2500);
FORCEADD OFFPAGE..1
(-7925 4600);
FORCEPROP 2 LAST $XR0 16 
J 0
(-8176 4600);
DISPLAY 0.638298 (-8176 4600);
PAINT MONO (-8176 4600);
FORCEPROP 2 LAST CDS_LIB mstr_standard
J 0
(-7925 4600);
DISPLAY 0.723404 (-7925 4600);
PAINT MONO (-7925 4600);
DISPLAY INVISIBLE (-7925 4600);
FORCEPROP 1 LAST OFFPAGE TRUE
J 0
(-7600 4475);
DISPLAY 0.872340 (-7600 4475);
PAINT GREEN (-7600 4475);
DISPLAY INVISIBLE (-7600 4475);
FORCEPROP 1 LAST COMMENT_BODY TRUE
J 0
(-7800 4500);
DISPLAY 0.872340 (-7800 4500);
PAINT GREEN (-7800 4500);
DISPLAY INVISIBLE (-7800 4500);
FORCEPROP 2 LAST PATH I19
J 0
(-8175 4650);
DISPLAY 1.021277 (-8175 4650);
DISPLAY INVISIBLE (-8175 4650);
FORCEADD Q_RES..2
R 2
(-8475 2300);
FORCEPROP 1 LAST LOCATION R95
J 2
(-8520 2425);
DISPLAY 0.489362 (-8520 2425);
PAINT SKYBLUE (-8520 2425);
FORCEPROP 0 LAST $SEC 1
J 0
(-8500 2475);
DISPLAY 0.680851 (-8500 2475);
PAINT MONO (-8500 2475);
DISPLAY INVISIBLE (-8500 2475);
FORCEPROP 0 LAST CDS_SEC 1
J 0
(-8500 2475);
DISPLAY 1.021277 (-8500 2475);
DISPLAY INVISIBLE (-8500 2475);
FORCEPROP 1 LASTPIN (-8475 2400) $PN 1
J 2
(-8480 2362);
DISPLAY 0.489362 (-8480 2362);
PAINT MONO (-8480 2362);
FORCEPROP 1 LASTPIN (-8475 2200) $PN 2
J 2
(-8480 2210);
DISPLAY 0.489362 (-8480 2210);
PAINT MONO (-8480 2210);
FORCEPROP 1 LAST PACK_TYPE 0402LF
J 2
(-8525 2250);
DISPLAY 0.489362 (-8525 2250);
PAINT SKYBLUE (-8525 2250);
FORCEPROP 1 LAST VALUE 1K
J 2
(-8520 2375);
DISPLAY 0.489362 (-8520 2375);
PAINT SKYBLUE (-8520 2375);
FORCEPROP 1 LAST TOLERANCE 1%
J 2
(-8525 2350);
DISPLAY 0.489362 (-8525 2350);
PAINT SKYBLUE (-8525 2350);
FORCEPROP 1 LAST WATTAGE 1/16W
J 2
(-8525 2325);
DISPLAY 0.489362 (-8525 2325);
PAINT SKYBLUE (-8525 2325);
FORCEPROP 1 LAST MATERIAL EMPTY
J 2
(-8525 2300);
DISPLAY 0.489362 (-8525 2300);
PAINT RED (-8525 2300);
FORCEPROP 2 LAST BOM_COST MEM
J 2
(-8525 2475);
DISPLAY 0.808511 (-8525 2475);
DISPLAY INVISIBLE (-8525 2475);
FORCEPROP 2 LAST CDS_LIB pure_quanta
J 2
(-8475 2300);
DISPLAY INVISIBLE (-8475 2300);
FORCEPROP 2 LAST ROOM 
J 2
(-8525 2525);
DISPLAY 0.808511 (-8525 2525);
PAINT RED (-8525 2525);
DISPLAY INVISIBLE (-8525 2525);
FORCEPROP 1 LAST PATH I190
J 2
(-8525 2475);
DISPLAY 0.978723 (-8525 2475);
PAINT WHITE (-8525 2475);
DISPLAY INVISIBLE (-8525 2475);
FORCEPROP 1 LAST PART_NUMBER CS21002FB06
J 2
(-8525 2275);
DISPLAY 0.489362 (-8525 2275);
PAINT SKYBLUE (-8525 2275);
DISPLAY INVISIBLE (-8525 2275);
FORCEADD OFFPAGE..2
(-2300 4575);
FORCEPROP 2 LAST $XR0 16 
J 0
(-2111 4575);
DISPLAY 0.638298 (-2111 4575);
PAINT MONO (-2111 4575);
FORCEPROP 2 LAST CDS_LIB mstr_standard
J 0
(-2300 4575);
DISPLAY 0.723404 (-2300 4575);
PAINT MONO (-2300 4575);
DISPLAY INVISIBLE (-2300 4575);
FORCEPROP 1 LAST OFFPAGE TRUE
J 0
(-1975 4450);
DISPLAY 0.723404 (-1975 4450);
PAINT GREEN (-1975 4450);
DISPLAY INVISIBLE (-1975 4450);
FORCEPROP 1 LAST COMMENT_BODY TRUE
J 0
(-2345 4480);
DISPLAY 0.872340 (-2345 4480);
PAINT GREEN (-2345 4480);
DISPLAY INVISIBLE (-2345 4480);
FORCEPROP 2 LAST PATH I192
J 0
(-2100 4625);
DISPLAY 0.680851 (-2100 4625);
DISPLAY INVISIBLE (-2100 4625);
FORCEADD OFFPAGE..2
(-2300 4625);
FORCEPROP 2 LAST $XR0 16 
J 0
(-2111 4625);
DISPLAY 0.638298 (-2111 4625);
PAINT MONO (-2111 4625);
FORCEPROP 2 LAST CDS_LIB mstr_standard
J 0
(-2300 4625);
DISPLAY 0.723404 (-2300 4625);
PAINT MONO (-2300 4625);
DISPLAY INVISIBLE (-2300 4625);
FORCEPROP 1 LAST OFFPAGE TRUE
J 0
(-1975 4500);
DISPLAY 0.723404 (-1975 4500);
PAINT GREEN (-1975 4500);
DISPLAY INVISIBLE (-1975 4500);
FORCEPROP 1 LAST COMMENT_BODY TRUE
J 0
(-2345 4530);
DISPLAY 0.872340 (-2345 4530);
PAINT GREEN (-2345 4530);
DISPLAY INVISIBLE (-2345 4530);
FORCEPROP 2 LAST PATH I193
J 0
(-2100 4675);
DISPLAY 0.680851 (-2100 4675);
DISPLAY INVISIBLE (-2100 4675);
FORCEADD OFFPAGE..2
(-2300 3525);
FORCEPROP 2 LAST $XR0 16 
J 0
(-2111 3525);
DISPLAY 0.638298 (-2111 3525);
PAINT MONO (-2111 3525);
FORCEPROP 2 LAST CDS_LIB mstr_standard
J 0
(-2300 3525);
DISPLAY 0.723404 (-2300 3525);
PAINT MONO (-2300 3525);
DISPLAY INVISIBLE (-2300 3525);
FORCEPROP 1 LAST OFFPAGE TRUE
J 0
(-1975 3400);
DISPLAY 0.723404 (-1975 3400);
PAINT GREEN (-1975 3400);
DISPLAY INVISIBLE (-1975 3400);
FORCEPROP 1 LAST COMMENT_BODY TRUE
J 0
(-2345 3430);
DISPLAY 0.872340 (-2345 3430);
PAINT GREEN (-2345 3430);
DISPLAY INVISIBLE (-2345 3430);
FORCEPROP 2 LAST PATH I194
J 0
(-2100 3575);
DISPLAY 0.680851 (-2100 3575);
DISPLAY INVISIBLE (-2100 3575);
FORCEADD OFFPAGE..2
(-2300 3575);
FORCEPROP 2 LAST $XR0 16 
J 0
(-2111 3575);
DISPLAY 0.638298 (-2111 3575);
PAINT MONO (-2111 3575);
FORCEPROP 2 LAST CDS_LIB mstr_standard
J 0
(-2300 3575);
DISPLAY 0.723404 (-2300 3575);
PAINT MONO (-2300 3575);
DISPLAY INVISIBLE (-2300 3575);
FORCEPROP 1 LAST OFFPAGE TRUE
J 0
(-1975 3450);
DISPLAY 0.723404 (-1975 3450);
PAINT GREEN (-1975 3450);
DISPLAY INVISIBLE (-1975 3450);
FORCEPROP 1 LAST COMMENT_BODY TRUE
J 0
(-2345 3480);
DISPLAY 0.872340 (-2345 3480);
PAINT GREEN (-2345 3480);
DISPLAY INVISIBLE (-2345 3480);
FORCEPROP 2 LAST PATH I195
J 0
(-2100 3625);
DISPLAY 0.680851 (-2100 3625);
DISPLAY INVISIBLE (-2100 3625);
FORCEADD TAP..1
(-2900 4525);
FORCEPROP 3 LASTPIN (-2950 4525) SIG_NAME M_G_CPU0_SA_DQS_DN<9>
J 0
(-2940 4535);
DISPLAY 0.659574 (-2940 4535);
PAINT MONO (-2940 4535);
DISPLAY INVISIBLE (-2940 4535);
FORCEPROP 1 LASTPIN (-2950 4525) BN 9
J 0
(-2962 4533);
DISPLAY 0.489362 (-2962 4533);
PAINT GREEN (-2962 4533);
FORCEPROP 2 LAST CDS_LIB mstr_standard
J 0
(-2900 4525);
DISPLAY 0.723404 (-2900 4525);
PAINT MONO (-2900 4525);
DISPLAY INVISIBLE (-2900 4525);
FORCEPROP 1 LAST BODY_TYPE PLUMBING
J 0
(-2900 4575);
DISPLAY 0.872340 (-2900 4575);
PAINT GREEN (-2900 4575);
DISPLAY INVISIBLE (-2900 4575);
FORCEPROP 1 LAST HDL_TAP TRUE
J 0
(-2575 4400);
DISPLAY 0.872340 (-2575 4400);
DISPLAY INVISIBLE (-2575 4400);
FORCEPROP 1 LAST PATH I196
J 0
(-2902 4525);
DISPLAY 0.872340 (-2902 4525);
PAINT GREEN (-2902 4525);
DISPLAY INVISIBLE (-2902 4525);
FORCEADD TAP..1
(-2900 4425);
FORCEPROP 3 LASTPIN (-2950 4425) SIG_NAME M_G_CPU0_SA_DQS_DN<8>
J 0
(-2940 4435);
DISPLAY 0.659574 (-2940 4435);
PAINT MONO (-2940 4435);
DISPLAY INVISIBLE (-2940 4435);
FORCEPROP 1 LASTPIN (-2950 4425) BN 8
J 0
(-2962 4433);
DISPLAY 0.489362 (-2962 4433);
PAINT GREEN (-2962 4433);
FORCEPROP 2 LAST CDS_LIB mstr_standard
J 0
(-2900 4425);
DISPLAY 0.723404 (-2900 4425);
PAINT MONO (-2900 4425);
DISPLAY INVISIBLE (-2900 4425);
FORCEPROP 1 LAST BODY_TYPE PLUMBING
J 0
(-2900 4475);
DISPLAY 0.872340 (-2900 4475);
PAINT GREEN (-2900 4475);
DISPLAY INVISIBLE (-2900 4475);
FORCEPROP 1 LAST HDL_TAP TRUE
J 0
(-2575 4300);
DISPLAY 0.872340 (-2575 4300);
DISPLAY INVISIBLE (-2575 4300);
FORCEPROP 1 LAST PATH I197
J 0
(-2902 4425);
DISPLAY 0.872340 (-2902 4425);
PAINT GREEN (-2902 4425);
DISPLAY INVISIBLE (-2902 4425);
FORCEADD TAP..1
(-3100 4575);
FORCEPROP 3 LASTPIN (-3150 4575) SIG_NAME M_G_CPU0_SA_DQS_DP<9>
J 0
(-3140 4585);
DISPLAY 0.659574 (-3140 4585);
PAINT MONO (-3140 4585);
DISPLAY INVISIBLE (-3140 4585);
FORCEPROP 1 LASTPIN (-3150 4575) BN 9
J 0
(-3162 4583);
DISPLAY 0.489362 (-3162 4583);
PAINT GREEN (-3162 4583);
FORCEPROP 2 LAST CDS_LIB mstr_standard
J 0
(-3100 4575);
DISPLAY 0.723404 (-3100 4575);
PAINT MONO (-3100 4575);
DISPLAY INVISIBLE (-3100 4575);
FORCEPROP 1 LAST BODY_TYPE PLUMBING
J 0
(-3100 4625);
DISPLAY 0.872340 (-3100 4625);
PAINT GREEN (-3100 4625);
DISPLAY INVISIBLE (-3100 4625);
FORCEPROP 1 LAST HDL_TAP TRUE
J 0
(-2775 4450);
DISPLAY 0.872340 (-2775 4450);
DISPLAY INVISIBLE (-2775 4450);
FORCEPROP 1 LAST PATH I198
J 0
(-3102 4575);
DISPLAY 0.872340 (-3102 4575);
PAINT GREEN (-3102 4575);
DISPLAY INVISIBLE (-3102 4575);
FORCEADD TAP..1
(-3100 4475);
FORCEPROP 3 LASTPIN (-3150 4475) SIG_NAME M_G_CPU0_SA_DQS_DP<8>
J 0
(-3140 4485);
DISPLAY 0.659574 (-3140 4485);
PAINT MONO (-3140 4485);
DISPLAY INVISIBLE (-3140 4485);
FORCEPROP 1 LASTPIN (-3150 4475) BN 8
J 0
(-3162 4483);
DISPLAY 0.489362 (-3162 4483);
PAINT GREEN (-3162 4483);
FORCEPROP 2 LAST CDS_LIB mstr_standard
J 0
(-3100 4475);
DISPLAY 0.723404 (-3100 4475);
PAINT MONO (-3100 4475);
DISPLAY INVISIBLE (-3100 4475);
FORCEPROP 1 LAST BODY_TYPE PLUMBING
J 0
(-3100 4525);
DISPLAY 0.872340 (-3100 4525);
PAINT GREEN (-3100 4525);
DISPLAY INVISIBLE (-3100 4525);
FORCEPROP 1 LAST HDL_TAP TRUE
J 0
(-2775 4350);
DISPLAY 0.872340 (-2775 4350);
DISPLAY INVISIBLE (-2775 4350);
FORCEPROP 1 LAST PATH I199
J 0
(-3102 4475);
DISPLAY 0.872340 (-3102 4475);
PAINT GREEN (-3102 4475);
DISPLAY INVISIBLE (-3102 4475);
FORCEADD OFFPAGE..5
(-7925 2000);
FORCEPROP 2 LAST $XR0 16 
J 0
(-8149 2000);
DISPLAY 0.638298 (-8149 2000);
PAINT MONO (-8149 2000);
FORCEPROP 2 LAST CDS_LIB mstr_standard
J 0
(-7925 2000);
DISPLAY 0.808511 (-7925 2000);
DISPLAY INVISIBLE (-7925 2000);
FORCEPROP 1 LAST OFFPAGE TRUE
J 0
(-7600 1875);
DISPLAY 0.872340 (-7600 1875);
PAINT GREEN (-7600 1875);
DISPLAY INVISIBLE (-7600 1875);
FORCEPROP 1 LAST COMMENT_BODY TRUE
J 0
(-7825 1925);
DISPLAY 0.872340 (-7825 1925);
PAINT GREEN (-7825 1925);
DISPLAY INVISIBLE (-7825 1925);
FORCEPROP 2 LAST PATH I2
J 0
(-8125 2050);
DISPLAY 1.021277 (-8125 2050);
DISPLAY INVISIBLE (-8125 2050);
FORCEADD OFFPAGE..1
(-7925 5050);
FORCEPROP 2 LAST $XR0 16 
J 0
(-8176 5050);
DISPLAY 0.638298 (-8176 5050);
PAINT MONO (-8176 5050);
FORCEPROP 2 LAST CDS_LIB mstr_standard
J 0
(-7925 5050);
DISPLAY 0.723404 (-7925 5050);
PAINT MONO (-7925 5050);
DISPLAY INVISIBLE (-7925 5050);
FORCEPROP 1 LAST OFFPAGE TRUE
J 0
(-7600 4925);
DISPLAY 0.872340 (-7600 4925);
PAINT GREEN (-7600 4925);
DISPLAY INVISIBLE (-7600 4925);
FORCEPROP 1 LAST COMMENT_BODY TRUE
J 0
(-7800 4950);
DISPLAY 0.872340 (-7800 4950);
PAINT GREEN (-7800 4950);
DISPLAY INVISIBLE (-7800 4950);
FORCEPROP 2 LAST PATH I20
J 0
(-8175 5100);
DISPLAY 1.021277 (-8175 5100);
DISPLAY INVISIBLE (-8175 5100);
FORCEADD TAP..1
(-3100 4375);
FORCEPROP 3 LASTPIN (-3150 4375) SIG_NAME M_G_CPU0_SA_DQS_DP<7>
J 0
(-3140 4385);
DISPLAY 0.659574 (-3140 4385);
PAINT MONO (-3140 4385);
DISPLAY INVISIBLE (-3140 4385);
FORCEPROP 1 LASTPIN (-3150 4375) BN 7
J 0
(-3162 4383);
DISPLAY 0.489362 (-3162 4383);
PAINT GREEN (-3162 4383);
FORCEPROP 2 LAST CDS_LIB mstr_standard
J 0
(-3100 4375);
DISPLAY 0.723404 (-3100 4375);
PAINT MONO (-3100 4375);
DISPLAY INVISIBLE (-3100 4375);
FORCEPROP 1 LAST BODY_TYPE PLUMBING
J 0
(-3100 4425);
DISPLAY 0.872340 (-3100 4425);
PAINT GREEN (-3100 4425);
DISPLAY INVISIBLE (-3100 4425);
FORCEPROP 1 LAST HDL_TAP TRUE
J 0
(-2775 4250);
DISPLAY 0.872340 (-2775 4250);
DISPLAY INVISIBLE (-2775 4250);
FORCEPROP 1 LAST PATH I200
J 0
(-3102 4375);
DISPLAY 0.872340 (-3102 4375);
PAINT GREEN (-3102 4375);
DISPLAY INVISIBLE (-3102 4375);
FORCEADD TAP..1
(-2900 4325);
FORCEPROP 3 LASTPIN (-2950 4325) SIG_NAME M_G_CPU0_SA_DQS_DN<7>
J 0
(-2940 4335);
DISPLAY 0.659574 (-2940 4335);
PAINT MONO (-2940 4335);
DISPLAY INVISIBLE (-2940 4335);
FORCEPROP 1 LASTPIN (-2950 4325) BN 7
J 0
(-2962 4333);
DISPLAY 0.489362 (-2962 4333);
PAINT GREEN (-2962 4333);
FORCEPROP 2 LAST CDS_LIB mstr_standard
J 0
(-2900 4325);
DISPLAY 0.723404 (-2900 4325);
PAINT MONO (-2900 4325);
DISPLAY INVISIBLE (-2900 4325);
FORCEPROP 1 LAST BODY_TYPE PLUMBING
J 0
(-2900 4375);
DISPLAY 0.872340 (-2900 4375);
PAINT GREEN (-2900 4375);
DISPLAY INVISIBLE (-2900 4375);
FORCEPROP 1 LAST HDL_TAP TRUE
J 0
(-2575 4200);
DISPLAY 0.872340 (-2575 4200);
DISPLAY INVISIBLE (-2575 4200);
FORCEPROP 1 LAST PATH I201
J 0
(-2902 4325);
DISPLAY 0.872340 (-2902 4325);
PAINT GREEN (-2902 4325);
DISPLAY INVISIBLE (-2902 4325);
FORCEADD TAP..1
(-2900 4125);
FORCEPROP 3 LASTPIN (-2950 4125) SIG_NAME M_G_CPU0_SA_DQS_DN<5>
J 0
(-2940 4135);
DISPLAY 0.659574 (-2940 4135);
PAINT MONO (-2940 4135);
DISPLAY INVISIBLE (-2940 4135);
FORCEPROP 1 LASTPIN (-2950 4125) BN 5
J 0
(-2962 4133);
DISPLAY 0.489362 (-2962 4133);
PAINT GREEN (-2962 4133);
FORCEPROP 2 LAST CDS_LIB mstr_standard
J 0
(-2900 4125);
DISPLAY 0.723404 (-2900 4125);
PAINT MONO (-2900 4125);
DISPLAY INVISIBLE (-2900 4125);
FORCEPROP 1 LAST BODY_TYPE PLUMBING
J 0
(-2900 4175);
DISPLAY 0.872340 (-2900 4175);
PAINT GREEN (-2900 4175);
DISPLAY INVISIBLE (-2900 4175);
FORCEPROP 1 LAST HDL_TAP TRUE
J 0
(-2575 4000);
DISPLAY 0.872340 (-2575 4000);
DISPLAY INVISIBLE (-2575 4000);
FORCEPROP 1 LAST PATH I202
J 0
(-2902 4125);
DISPLAY 0.872340 (-2902 4125);
PAINT GREEN (-2902 4125);
DISPLAY INVISIBLE (-2902 4125);
FORCEADD TAP..1
(-2900 4225);
FORCEPROP 3 LASTPIN (-2950 4225) SIG_NAME M_G_CPU0_SA_DQS_DN<6>
J 0
(-2940 4235);
DISPLAY 0.659574 (-2940 4235);
PAINT MONO (-2940 4235);
DISPLAY INVISIBLE (-2940 4235);
FORCEPROP 1 LASTPIN (-2950 4225) BN 6
J 0
(-2962 4233);
DISPLAY 0.489362 (-2962 4233);
PAINT GREEN (-2962 4233);
FORCEPROP 2 LAST CDS_LIB mstr_standard
J 0
(-2900 4225);
DISPLAY 0.723404 (-2900 4225);
PAINT MONO (-2900 4225);
DISPLAY INVISIBLE (-2900 4225);
FORCEPROP 1 LAST BODY_TYPE PLUMBING
J 0
(-2900 4275);
DISPLAY 0.872340 (-2900 4275);
PAINT GREEN (-2900 4275);
DISPLAY INVISIBLE (-2900 4275);
FORCEPROP 1 LAST HDL_TAP TRUE
J 0
(-2575 4100);
DISPLAY 0.872340 (-2575 4100);
DISPLAY INVISIBLE (-2575 4100);
FORCEPROP 1 LAST PATH I203
J 0
(-2902 4225);
DISPLAY 0.872340 (-2902 4225);
PAINT GREEN (-2902 4225);
DISPLAY INVISIBLE (-2902 4225);
FORCEADD TAP..1
(-2900 4025);
FORCEPROP 3 LASTPIN (-2950 4025) SIG_NAME M_G_CPU0_SA_DQS_DN<4>
J 0
(-2940 4035);
DISPLAY 0.659574 (-2940 4035);
PAINT MONO (-2940 4035);
DISPLAY INVISIBLE (-2940 4035);
FORCEPROP 1 LASTPIN (-2950 4025) BN 4
J 0
(-2962 4033);
DISPLAY 0.489362 (-2962 4033);
PAINT GREEN (-2962 4033);
FORCEPROP 2 LAST CDS_LIB mstr_standard
J 0
(-2900 4025);
DISPLAY 0.723404 (-2900 4025);
PAINT MONO (-2900 4025);
DISPLAY INVISIBLE (-2900 4025);
FORCEPROP 1 LAST BODY_TYPE PLUMBING
J 0
(-2900 4075);
DISPLAY 0.872340 (-2900 4075);
PAINT GREEN (-2900 4075);
DISPLAY INVISIBLE (-2900 4075);
FORCEPROP 1 LAST HDL_TAP TRUE
J 0
(-2575 3900);
DISPLAY 0.872340 (-2575 3900);
DISPLAY INVISIBLE (-2575 3900);
FORCEPROP 1 LAST PATH I204
J 0
(-2902 4025);
DISPLAY 0.872340 (-2902 4025);
PAINT GREEN (-2902 4025);
DISPLAY INVISIBLE (-2902 4025);
FORCEADD TAP..1
(-2900 3925);
FORCEPROP 3 LASTPIN (-2950 3925) SIG_NAME M_G_CPU0_SA_DQS_DN<3>
J 0
(-2940 3935);
DISPLAY 0.659574 (-2940 3935);
PAINT MONO (-2940 3935);
DISPLAY INVISIBLE (-2940 3935);
FORCEPROP 1 LASTPIN (-2950 3925) BN 3
J 0
(-2962 3933);
DISPLAY 0.489362 (-2962 3933);
PAINT GREEN (-2962 3933);
FORCEPROP 2 LAST CDS_LIB mstr_standard
J 0
(-2900 3925);
DISPLAY 0.723404 (-2900 3925);
PAINT MONO (-2900 3925);
DISPLAY INVISIBLE (-2900 3925);
FORCEPROP 1 LAST BODY_TYPE PLUMBING
J 0
(-2900 3975);
DISPLAY 0.872340 (-2900 3975);
PAINT GREEN (-2900 3975);
DISPLAY INVISIBLE (-2900 3975);
FORCEPROP 1 LAST HDL_TAP TRUE
J 0
(-2575 3800);
DISPLAY 0.872340 (-2575 3800);
DISPLAY INVISIBLE (-2575 3800);
FORCEPROP 1 LAST PATH I205
J 0
(-2902 3925);
DISPLAY 0.872340 (-2902 3925);
PAINT GREEN (-2902 3925);
DISPLAY INVISIBLE (-2902 3925);
FORCEADD TAP..1
(-3100 4175);
FORCEPROP 3 LASTPIN (-3150 4175) SIG_NAME M_G_CPU0_SA_DQS_DP<5>
J 0
(-3140 4185);
DISPLAY 0.659574 (-3140 4185);
PAINT MONO (-3140 4185);
DISPLAY INVISIBLE (-3140 4185);
FORCEPROP 1 LASTPIN (-3150 4175) BN 5
J 0
(-3162 4183);
DISPLAY 0.489362 (-3162 4183);
PAINT GREEN (-3162 4183);
FORCEPROP 2 LAST CDS_LIB mstr_standard
J 0
(-3100 4175);
DISPLAY 0.723404 (-3100 4175);
PAINT MONO (-3100 4175);
DISPLAY INVISIBLE (-3100 4175);
FORCEPROP 1 LAST BODY_TYPE PLUMBING
J 0
(-3100 4225);
DISPLAY 0.872340 (-3100 4225);
PAINT GREEN (-3100 4225);
DISPLAY INVISIBLE (-3100 4225);
FORCEPROP 1 LAST HDL_TAP TRUE
J 0
(-2775 4050);
DISPLAY 0.872340 (-2775 4050);
DISPLAY INVISIBLE (-2775 4050);
FORCEPROP 1 LAST PATH I206
J 0
(-3102 4175);
DISPLAY 0.872340 (-3102 4175);
PAINT GREEN (-3102 4175);
DISPLAY INVISIBLE (-3102 4175);
FORCEADD TAP..1
(-3100 4275);
FORCEPROP 3 LASTPIN (-3150 4275) SIG_NAME M_G_CPU0_SA_DQS_DP<6>
J 0
(-3140 4285);
DISPLAY 0.659574 (-3140 4285);
PAINT MONO (-3140 4285);
DISPLAY INVISIBLE (-3140 4285);
FORCEPROP 1 LASTPIN (-3150 4275) BN 6
J 0
(-3162 4283);
DISPLAY 0.489362 (-3162 4283);
PAINT GREEN (-3162 4283);
FORCEPROP 2 LAST CDS_LIB mstr_standard
J 0
(-3100 4275);
DISPLAY 0.723404 (-3100 4275);
PAINT MONO (-3100 4275);
DISPLAY INVISIBLE (-3100 4275);
FORCEPROP 1 LAST BODY_TYPE PLUMBING
J 0
(-3100 4325);
DISPLAY 0.872340 (-3100 4325);
PAINT GREEN (-3100 4325);
DISPLAY INVISIBLE (-3100 4325);
FORCEPROP 1 LAST HDL_TAP TRUE
J 0
(-2775 4150);
DISPLAY 0.872340 (-2775 4150);
DISPLAY INVISIBLE (-2775 4150);
FORCEPROP 1 LAST PATH I207
J 0
(-3102 4275);
DISPLAY 0.872340 (-3102 4275);
PAINT GREEN (-3102 4275);
DISPLAY INVISIBLE (-3102 4275);
FORCEADD TAP..1
(-3100 4075);
FORCEPROP 3 LASTPIN (-3150 4075) SIG_NAME M_G_CPU0_SA_DQS_DP<4>
J 0
(-3140 4085);
DISPLAY 0.659574 (-3140 4085);
PAINT MONO (-3140 4085);
DISPLAY INVISIBLE (-3140 4085);
FORCEPROP 1 LASTPIN (-3150 4075) BN 4
J 0
(-3162 4083);
DISPLAY 0.489362 (-3162 4083);
PAINT GREEN (-3162 4083);
FORCEPROP 2 LAST CDS_LIB mstr_standard
J 0
(-3100 4075);
DISPLAY 0.723404 (-3100 4075);
PAINT MONO (-3100 4075);
DISPLAY INVISIBLE (-3100 4075);
FORCEPROP 1 LAST BODY_TYPE PLUMBING
J 0
(-3100 4125);
DISPLAY 0.872340 (-3100 4125);
PAINT GREEN (-3100 4125);
DISPLAY INVISIBLE (-3100 4125);
FORCEPROP 1 LAST HDL_TAP TRUE
J 0
(-2775 3950);
DISPLAY 0.872340 (-2775 3950);
DISPLAY INVISIBLE (-2775 3950);
FORCEPROP 1 LAST PATH I208
J 0
(-3102 4075);
DISPLAY 0.872340 (-3102 4075);
PAINT GREEN (-3102 4075);
DISPLAY INVISIBLE (-3102 4075);
FORCEADD TAP..1
(-3100 3875);
FORCEPROP 3 LASTPIN (-3150 3875) SIG_NAME M_G_CPU0_SA_DQS_DP<2>
J 0
(-3140 3885);
DISPLAY 0.659574 (-3140 3885);
PAINT MONO (-3140 3885);
DISPLAY INVISIBLE (-3140 3885);
FORCEPROP 1 LASTPIN (-3150 3875) BN 2
J 0
(-3162 3883);
DISPLAY 0.489362 (-3162 3883);
PAINT GREEN (-3162 3883);
FORCEPROP 2 LAST CDS_LIB mstr_standard
J 0
(-3100 3875);
DISPLAY 0.723404 (-3100 3875);
PAINT MONO (-3100 3875);
DISPLAY INVISIBLE (-3100 3875);
FORCEPROP 1 LAST BODY_TYPE PLUMBING
J 0
(-3100 3925);
DISPLAY 0.872340 (-3100 3925);
PAINT GREEN (-3100 3925);
DISPLAY INVISIBLE (-3100 3925);
FORCEPROP 1 LAST HDL_TAP TRUE
J 0
(-2775 3750);
DISPLAY 0.872340 (-2775 3750);
DISPLAY INVISIBLE (-2775 3750);
FORCEPROP 1 LAST PATH I209
J 0
(-3102 3875);
DISPLAY 0.872340 (-3102 3875);
PAINT GREEN (-3102 3875);
DISPLAY INVISIBLE (-3102 3875);
FORCEADD OFFPAGE..1
(-7925 5450);
FORCEPROP 2 LAST $XR0 16 
J 0
(-8176 5450);
DISPLAY 0.638298 (-8176 5450);
PAINT MONO (-8176 5450);
FORCEPROP 2 LAST CDS_LIB mstr_standard
J 0
(-7925 5450);
DISPLAY 0.723404 (-7925 5450);
PAINT MONO (-7925 5450);
DISPLAY INVISIBLE (-7925 5450);
FORCEPROP 1 LAST OFFPAGE TRUE
J 0
(-7600 5325);
DISPLAY 0.872340 (-7600 5325);
PAINT GREEN (-7600 5325);
DISPLAY INVISIBLE (-7600 5325);
FORCEPROP 1 LAST COMMENT_BODY TRUE
J 0
(-7800 5350);
DISPLAY 0.872340 (-7800 5350);
PAINT GREEN (-7800 5350);
DISPLAY INVISIBLE (-7800 5350);
FORCEPROP 2 LAST PATH I21
J 0
(-8175 5500);
DISPLAY 1.021277 (-8175 5500);
DISPLAY INVISIBLE (-8175 5500);
FORCEADD TAP..1
(-3100 3975);
FORCEPROP 3 LASTPIN (-3150 3975) SIG_NAME M_G_CPU0_SA_DQS_DP<3>
J 0
(-3140 3985);
DISPLAY 0.659574 (-3140 3985);
PAINT MONO (-3140 3985);
DISPLAY INVISIBLE (-3140 3985);
FORCEPROP 1 LASTPIN (-3150 3975) BN 3
J 0
(-3162 3983);
DISPLAY 0.489362 (-3162 3983);
PAINT GREEN (-3162 3983);
FORCEPROP 2 LAST CDS_LIB mstr_standard
J 0
(-3100 3975);
DISPLAY 0.723404 (-3100 3975);
PAINT MONO (-3100 3975);
DISPLAY INVISIBLE (-3100 3975);
FORCEPROP 1 LAST BODY_TYPE PLUMBING
J 0
(-3100 4025);
DISPLAY 0.872340 (-3100 4025);
PAINT GREEN (-3100 4025);
DISPLAY INVISIBLE (-3100 4025);
FORCEPROP 1 LAST HDL_TAP TRUE
J 0
(-2775 3850);
DISPLAY 0.872340 (-2775 3850);
DISPLAY INVISIBLE (-2775 3850);
FORCEPROP 1 LAST PATH I210
J 0
(-3102 3975);
DISPLAY 0.872340 (-3102 3975);
PAINT GREEN (-3102 3975);
DISPLAY INVISIBLE (-3102 3975);
FORCEADD TAP..1
(-2900 3825);
FORCEPROP 3 LASTPIN (-2950 3825) SIG_NAME M_G_CPU0_SA_DQS_DN<2>
J 0
(-2940 3835);
DISPLAY 0.659574 (-2940 3835);
PAINT MONO (-2940 3835);
DISPLAY INVISIBLE (-2940 3835);
FORCEPROP 1 LASTPIN (-2950 3825) BN 2
J 0
(-2962 3833);
DISPLAY 0.489362 (-2962 3833);
PAINT GREEN (-2962 3833);
FORCEPROP 2 LAST CDS_LIB mstr_standard
J 0
(-2900 3825);
DISPLAY 0.723404 (-2900 3825);
PAINT MONO (-2900 3825);
DISPLAY INVISIBLE (-2900 3825);
FORCEPROP 1 LAST BODY_TYPE PLUMBING
J 0
(-2900 3875);
DISPLAY 0.872340 (-2900 3875);
PAINT GREEN (-2900 3875);
DISPLAY INVISIBLE (-2900 3875);
FORCEPROP 1 LAST HDL_TAP TRUE
J 0
(-2575 3700);
DISPLAY 0.872340 (-2575 3700);
DISPLAY INVISIBLE (-2575 3700);
FORCEPROP 1 LAST PATH I211
J 0
(-2902 3825);
DISPLAY 0.872340 (-2902 3825);
PAINT GREEN (-2902 3825);
DISPLAY INVISIBLE (-2902 3825);
FORCEADD TAP..1
(-2900 3725);
FORCEPROP 3 LASTPIN (-2950 3725) SIG_NAME M_G_CPU0_SA_DQS_DN<1>
J 0
(-2940 3735);
DISPLAY 0.659574 (-2940 3735);
PAINT MONO (-2940 3735);
DISPLAY INVISIBLE (-2940 3735);
FORCEPROP 1 LASTPIN (-2950 3725) BN 1
J 0
(-2962 3733);
DISPLAY 0.489362 (-2962 3733);
PAINT GREEN (-2962 3733);
FORCEPROP 2 LAST CDS_LIB mstr_standard
J 0
(-2900 3725);
DISPLAY 0.723404 (-2900 3725);
PAINT MONO (-2900 3725);
DISPLAY INVISIBLE (-2900 3725);
FORCEPROP 1 LAST BODY_TYPE PLUMBING
J 0
(-2900 3775);
DISPLAY 0.872340 (-2900 3775);
PAINT GREEN (-2900 3775);
DISPLAY INVISIBLE (-2900 3775);
FORCEPROP 1 LAST HDL_TAP TRUE
J 0
(-2575 3600);
DISPLAY 0.872340 (-2575 3600);
DISPLAY INVISIBLE (-2575 3600);
FORCEPROP 1 LAST PATH I212
J 0
(-2902 3725);
DISPLAY 0.872340 (-2902 3725);
PAINT GREEN (-2902 3725);
DISPLAY INVISIBLE (-2902 3725);
FORCEADD TAP..1
(-2900 3625);
FORCEPROP 3 LASTPIN (-2950 3625) SIG_NAME M_G_CPU0_SA_DQS_DN<0>
J 0
(-2940 3635);
DISPLAY 0.659574 (-2940 3635);
PAINT MONO (-2940 3635);
DISPLAY INVISIBLE (-2940 3635);
FORCEPROP 1 LASTPIN (-2950 3625) BN 0
J 0
(-2962 3633);
DISPLAY 0.489362 (-2962 3633);
PAINT GREEN (-2962 3633);
FORCEPROP 2 LAST CDS_LIB mstr_standard
J 0
(-2900 3625);
DISPLAY 0.723404 (-2900 3625);
PAINT MONO (-2900 3625);
DISPLAY INVISIBLE (-2900 3625);
FORCEPROP 1 LAST BODY_TYPE PLUMBING
J 0
(-2900 3675);
DISPLAY 0.872340 (-2900 3675);
PAINT GREEN (-2900 3675);
DISPLAY INVISIBLE (-2900 3675);
FORCEPROP 1 LAST HDL_TAP TRUE
J 0
(-2575 3500);
DISPLAY 0.872340 (-2575 3500);
DISPLAY INVISIBLE (-2575 3500);
FORCEPROP 1 LAST PATH I213
J 0
(-2902 3625);
DISPLAY 0.872340 (-2902 3625);
PAINT GREEN (-2902 3625);
DISPLAY INVISIBLE (-2902 3625);
FORCEADD TAP..1
(-2900 3475);
FORCEPROP 3 LASTPIN (-2950 3475) SIG_NAME M_G_CPU0_SB_DQS_DN<9>
J 0
(-2940 3485);
DISPLAY 0.659574 (-2940 3485);
PAINT MONO (-2940 3485);
DISPLAY INVISIBLE (-2940 3485);
FORCEPROP 1 LASTPIN (-2950 3475) BN 9
J 0
(-2962 3483);
DISPLAY 0.489362 (-2962 3483);
PAINT GREEN (-2962 3483);
FORCEPROP 2 LAST CDS_LIB mstr_standard
J 0
(-2900 3475);
DISPLAY 0.723404 (-2900 3475);
PAINT MONO (-2900 3475);
DISPLAY INVISIBLE (-2900 3475);
FORCEPROP 1 LAST BODY_TYPE PLUMBING
J 0
(-2900 3525);
DISPLAY 0.872340 (-2900 3525);
PAINT GREEN (-2900 3525);
DISPLAY INVISIBLE (-2900 3525);
FORCEPROP 1 LAST HDL_TAP TRUE
J 0
(-2575 3350);
DISPLAY 0.872340 (-2575 3350);
DISPLAY INVISIBLE (-2575 3350);
FORCEPROP 1 LAST PATH I214
J 0
(-2902 3475);
DISPLAY 0.872340 (-2902 3475);
PAINT GREEN (-2902 3475);
DISPLAY INVISIBLE (-2902 3475);
FORCEADD TAP..1
(-2900 3375);
FORCEPROP 3 LASTPIN (-2950 3375) SIG_NAME M_G_CPU0_SB_DQS_DN<8>
J 0
(-2940 3385);
DISPLAY 0.659574 (-2940 3385);
PAINT MONO (-2940 3385);
DISPLAY INVISIBLE (-2940 3385);
FORCEPROP 1 LASTPIN (-2950 3375) BN 8
J 0
(-2962 3383);
DISPLAY 0.489362 (-2962 3383);
PAINT GREEN (-2962 3383);
FORCEPROP 2 LAST CDS_LIB mstr_standard
J 0
(-2900 3375);
DISPLAY 0.723404 (-2900 3375);
PAINT MONO (-2900 3375);
DISPLAY INVISIBLE (-2900 3375);
FORCEPROP 1 LAST BODY_TYPE PLUMBING
J 0
(-2900 3425);
DISPLAY 0.872340 (-2900 3425);
PAINT GREEN (-2900 3425);
DISPLAY INVISIBLE (-2900 3425);
FORCEPROP 1 LAST HDL_TAP TRUE
J 0
(-2575 3250);
DISPLAY 0.872340 (-2575 3250);
DISPLAY INVISIBLE (-2575 3250);
FORCEPROP 1 LAST PATH I215
J 0
(-2902 3375);
DISPLAY 0.872340 (-2902 3375);
PAINT GREEN (-2902 3375);
DISPLAY INVISIBLE (-2902 3375);
FORCEADD TAP..1
(-3100 3675);
FORCEPROP 3 LASTPIN (-3150 3675) SIG_NAME M_G_CPU0_SA_DQS_DP<0>
J 0
(-3140 3685);
DISPLAY 0.659574 (-3140 3685);
PAINT MONO (-3140 3685);
DISPLAY INVISIBLE (-3140 3685);
FORCEPROP 1 LASTPIN (-3150 3675) BN 0
J 0
(-3162 3683);
DISPLAY 0.489362 (-3162 3683);
PAINT GREEN (-3162 3683);
FORCEPROP 2 LAST CDS_LIB mstr_standard
J 0
(-3100 3675);
DISPLAY 0.723404 (-3100 3675);
PAINT MONO (-3100 3675);
DISPLAY INVISIBLE (-3100 3675);
FORCEPROP 1 LAST BODY_TYPE PLUMBING
J 0
(-3100 3725);
DISPLAY 0.872340 (-3100 3725);
PAINT GREEN (-3100 3725);
DISPLAY INVISIBLE (-3100 3725);
FORCEPROP 1 LAST HDL_TAP TRUE
J 0
(-2775 3550);
DISPLAY 0.872340 (-2775 3550);
DISPLAY INVISIBLE (-2775 3550);
FORCEPROP 1 LAST PATH I216
J 0
(-3102 3675);
DISPLAY 0.872340 (-3102 3675);
PAINT GREEN (-3102 3675);
DISPLAY INVISIBLE (-3102 3675);
FORCEADD TAP..1
(-3100 3775);
FORCEPROP 3 LASTPIN (-3150 3775) SIG_NAME M_G_CPU0_SA_DQS_DP<1>
J 0
(-3140 3785);
DISPLAY 0.659574 (-3140 3785);
PAINT MONO (-3140 3785);
DISPLAY INVISIBLE (-3140 3785);
FORCEPROP 1 LASTPIN (-3150 3775) BN 1
J 0
(-3162 3783);
DISPLAY 0.489362 (-3162 3783);
PAINT GREEN (-3162 3783);
FORCEPROP 2 LAST CDS_LIB mstr_standard
J 0
(-3100 3775);
DISPLAY 0.723404 (-3100 3775);
PAINT MONO (-3100 3775);
DISPLAY INVISIBLE (-3100 3775);
FORCEPROP 1 LAST BODY_TYPE PLUMBING
J 0
(-3100 3825);
DISPLAY 0.872340 (-3100 3825);
PAINT GREEN (-3100 3825);
DISPLAY INVISIBLE (-3100 3825);
FORCEPROP 1 LAST HDL_TAP TRUE
J 0
(-2775 3650);
DISPLAY 0.872340 (-2775 3650);
DISPLAY INVISIBLE (-2775 3650);
FORCEPROP 1 LAST PATH I217
J 0
(-3102 3775);
DISPLAY 0.872340 (-3102 3775);
PAINT GREEN (-3102 3775);
DISPLAY INVISIBLE (-3102 3775);
FORCEADD TAP..1
(-3100 3425);
FORCEPROP 3 LASTPIN (-3150 3425) SIG_NAME M_G_CPU0_SB_DQS_DP<8>
J 0
(-3140 3435);
DISPLAY 0.659574 (-3140 3435);
PAINT MONO (-3140 3435);
DISPLAY INVISIBLE (-3140 3435);
FORCEPROP 1 LASTPIN (-3150 3425) BN 8
J 0
(-3162 3433);
DISPLAY 0.489362 (-3162 3433);
PAINT GREEN (-3162 3433);
FORCEPROP 2 LAST CDS_LIB mstr_standard
J 0
(-3100 3425);
DISPLAY 0.723404 (-3100 3425);
PAINT MONO (-3100 3425);
DISPLAY INVISIBLE (-3100 3425);
FORCEPROP 1 LAST BODY_TYPE PLUMBING
J 0
(-3100 3475);
DISPLAY 0.872340 (-3100 3475);
PAINT GREEN (-3100 3475);
DISPLAY INVISIBLE (-3100 3475);
FORCEPROP 1 LAST HDL_TAP TRUE
J 0
(-2775 3300);
DISPLAY 0.872340 (-2775 3300);
DISPLAY INVISIBLE (-2775 3300);
FORCEPROP 1 LAST PATH I218
J 0
(-3102 3425);
DISPLAY 0.872340 (-3102 3425);
PAINT GREEN (-3102 3425);
DISPLAY INVISIBLE (-3102 3425);
FORCEADD TAP..1
(-3100 3525);
FORCEPROP 3 LASTPIN (-3150 3525) SIG_NAME M_G_CPU0_SB_DQS_DP<9>
J 0
(-3140 3535);
DISPLAY 0.659574 (-3140 3535);
PAINT MONO (-3140 3535);
DISPLAY INVISIBLE (-3140 3535);
FORCEPROP 1 LASTPIN (-3150 3525) BN 9
J 0
(-3162 3533);
DISPLAY 0.489362 (-3162 3533);
PAINT GREEN (-3162 3533);
FORCEPROP 2 LAST CDS_LIB mstr_standard
J 0
(-3100 3525);
DISPLAY 0.723404 (-3100 3525);
PAINT MONO (-3100 3525);
DISPLAY INVISIBLE (-3100 3525);
FORCEPROP 1 LAST BODY_TYPE PLUMBING
J 0
(-3100 3575);
DISPLAY 0.872340 (-3100 3575);
PAINT GREEN (-3100 3575);
DISPLAY INVISIBLE (-3100 3575);
FORCEPROP 1 LAST HDL_TAP TRUE
J 0
(-2775 3400);
DISPLAY 0.872340 (-2775 3400);
DISPLAY INVISIBLE (-2775 3400);
FORCEPROP 1 LAST PATH I219
J 0
(-3102 3525);
DISPLAY 0.872340 (-3102 3525);
PAINT GREEN (-3102 3525);
DISPLAY INVISIBLE (-3102 3525);
FORCEADD SCONN288_DDR506112002KQ..1
(-6475 3650);
FORCEPROP 1 LAST LOCATION J16
J 0
(-6925 5725);
DISPLAY 0.468085 (-6925 5725);
PAINT SKYBLUE (-6925 5725);
FORCEPROP 0 LAST $SEC 1
J 0
(-6925 5875);
DISPLAY 0.680851 (-6925 5875);
PAINT MONO (-6925 5875);
DISPLAY INVISIBLE (-6925 5875);
FORCEPROP 0 LAST CDS_SEC 1
J 0
(-6925 5875);
DISPLAY 0.680851 (-6925 5875);
DISPLAY INVISIBLE (-6925 5875);
FORCEPROP 0 LASTPIN (-7075 3050) $PN 62
J 2
(-7085 3060);
DISPLAY 0.680851 (-7085 3060);
PAINT MONO (-7085 3060);
FORCEPROP 0 LASTPIN (-7075 5100) $PN 66
J 2
(-7085 5110);
DISPLAY 0.680851 (-7085 5110);
PAINT MONO (-7085 5110);
FORCEPROP 0 LASTPIN (-7075 4700) $PN 76
J 2
(-7085 4710);
DISPLAY 0.680851 (-7085 4710);
PAINT MONO (-7085 4710);
FORCEPROP 0 LASTPIN (-7075 5150) $PN 211
J 2
(-7085 5160);
DISPLAY 0.680851 (-7085 5160);
PAINT MONO (-7085 5160);
FORCEPROP 0 LASTPIN (-7075 4750) $PN 221
J 2
(-7085 4760);
DISPLAY 0.680851 (-7085 4760);
PAINT MONO (-7085 4760);
FORCEPROP 0 LASTPIN (-7075 5200) $PN 68
J 2
(-7085 5210);
DISPLAY 0.680851 (-7085 5210);
PAINT MONO (-7085 5210);
FORCEPROP 0 LASTPIN (-7075 4800) $PN 78
J 2
(-7085 4810);
DISPLAY 0.680851 (-7085 4810);
PAINT MONO (-7085 4810);
FORCEPROP 0 LASTPIN (-7075 5250) $PN 213
J 2
(-7085 5260);
DISPLAY 0.680851 (-7085 5260);
PAINT MONO (-7085 5260);
FORCEPROP 0 LASTPIN (-7075 4850) $PN 223
J 2
(-7085 4860);
DISPLAY 0.680851 (-7085 4860);
PAINT MONO (-7085 4860);
FORCEPROP 0 LASTPIN (-7075 5300) $PN 70
J 2
(-7085 5310);
DISPLAY 0.680851 (-7085 5310);
PAINT MONO (-7085 5310);
FORCEPROP 0 LASTPIN (-7075 4900) $PN 80
J 2
(-7085 4910);
DISPLAY 0.680851 (-7085 4910);
PAINT MONO (-7085 4910);
FORCEPROP 0 LASTPIN (-7075 5350) $PN 215
J 2
(-7085 5360);
DISPLAY 0.680851 (-7085 5360);
PAINT MONO (-7085 5360);
FORCEPROP 0 LASTPIN (-7075 4950) $PN 225
J 2
(-7085 4960);
DISPLAY 0.680851 (-7085 4960);
PAINT MONO (-7085 4960);
FORCEPROP 0 LASTPIN (-7075 5400) $PN 72
J 2
(-7085 5410);
DISPLAY 0.680851 (-7085 5410);
PAINT MONO (-7085 5410);
FORCEPROP 0 LASTPIN (-7075 5000) $PN 82
J 2
(-7085 5010);
DISPLAY 0.680851 (-7085 5010);
PAINT MONO (-7085 5010);
FORCEPROP 0 LASTPIN (-7075 3650) $PN 51
J 2
(-7085 3660);
DISPLAY 0.680851 (-7085 3660);
PAINT MONO (-7085 3660);
FORCEPROP 0 LASTPIN (-7075 3200) $PN 96
J 2
(-7085 3210);
DISPLAY 0.680851 (-7085 3210);
PAINT MONO (-7085 3210);
FORCEPROP 0 LASTPIN (-7075 3700) $PN 53
J 2
(-7085 3710);
DISPLAY 0.680851 (-7085 3710);
PAINT MONO (-7085 3710);
FORCEPROP 0 LASTPIN (-7075 3250) $PN 98
J 2
(-7085 3260);
DISPLAY 0.680851 (-7085 3260);
PAINT MONO (-7085 3260);
FORCEPROP 0 LASTPIN (-7075 3750) $PN 196
J 2
(-7085 3760);
DISPLAY 0.680851 (-7085 3760);
PAINT MONO (-7085 3760);
FORCEPROP 0 LASTPIN (-7075 3300) $PN 241
J 2
(-7085 3310);
DISPLAY 0.680851 (-7085 3310);
PAINT MONO (-7085 3310);
FORCEPROP 0 LASTPIN (-7075 3800) $PN 198
J 2
(-7085 3810);
DISPLAY 0.680851 (-7085 3810);
PAINT MONO (-7085 3810);
FORCEPROP 0 LASTPIN (-7075 3350) $PN 243
J 2
(-7085 3360);
DISPLAY 0.680851 (-7085 3360);
PAINT MONO (-7085 3360);
FORCEPROP 0 LASTPIN (-7075 3850) $PN 58
J 2
(-7085 3860);
DISPLAY 0.680851 (-7085 3860);
PAINT MONO (-7085 3860);
FORCEPROP 0 LASTPIN (-7075 3400) $PN 89
J 2
(-7085 3410);
DISPLAY 0.680851 (-7085 3410);
PAINT MONO (-7085 3410);
FORCEPROP 0 LASTPIN (-7075 3900) $PN 60
J 2
(-7085 3910);
DISPLAY 0.680851 (-7085 3910);
PAINT MONO (-7085 3910);
FORCEPROP 0 LASTPIN (-7075 3450) $PN 91
J 2
(-7085 3460);
DISPLAY 0.680851 (-7085 3460);
PAINT MONO (-7085 3460);
FORCEPROP 0 LASTPIN (-7075 3950) $PN 203
J 2
(-7085 3960);
DISPLAY 0.680851 (-7085 3960);
PAINT MONO (-7085 3960);
FORCEPROP 0 LASTPIN (-7075 3500) $PN 234
J 2
(-7085 3510);
DISPLAY 0.680851 (-7085 3510);
PAINT MONO (-7085 3510);
FORCEPROP 0 LASTPIN (-7075 4000) $PN 205
J 2
(-7085 4010);
DISPLAY 0.680851 (-7085 4010);
PAINT MONO (-7085 4010);
FORCEPROP 0 LASTPIN (-7075 3550) $PN 236
J 2
(-7085 3560);
DISPLAY 0.680851 (-7085 3560);
PAINT MONO (-7085 3560);
FORCEPROP 0 LASTPIN (-7075 4100) $PN 218
J 2
(-7085 4110);
DISPLAY 0.680851 (-7085 4110);
PAINT MONO (-7085 4110);
FORCEPROP 0 LASTPIN (-7075 4150) $PN 217
J 2
(-7085 4160);
DISPLAY 0.680851 (-7085 4160);
PAINT MONO (-7085 4160);
FORCEPROP 0 LASTPIN (-7075 4400) $PN 64
J 2
(-7085 4410);
DISPLAY 0.680851 (-7085 4410);
PAINT MONO (-7085 4410);
FORCEPROP 0 LASTPIN (-7075 4250) $PN 84
J 2
(-7085 4260);
DISPLAY 0.680851 (-7085 4260);
PAINT MONO (-7085 4260);
FORCEPROP 0 LASTPIN (-7075 4450) $PN 209
J 2
(-7085 4460);
DISPLAY 0.680851 (-7085 4460);
PAINT MONO (-7085 4460);
FORCEPROP 0 LASTPIN (-7075 4300) $PN 229
J 2
(-7085 4310);
DISPLAY 0.680851 (-7085 4310);
PAINT MONO (-7085 4310);
FORCEPROP 0 LASTPIN (-5875 3850) $PN 7
J 0
(-5865 3860);
DISPLAY 0.680851 (-5865 3860);
PAINT MONO (-5865 3860);
FORCEPROP 0 LASTPIN (-5875 2200) $PN 100
J 0
(-5865 2210);
DISPLAY 0.680851 (-5865 2210);
PAINT MONO (-5865 2210);
FORCEPROP 0 LASTPIN (-5875 3900) $PN 9
J 0
(-5865 3910);
DISPLAY 0.680851 (-5865 3910);
PAINT MONO (-5865 3910);
FORCEPROP 0 LASTPIN (-5875 2250) $PN 102
J 0
(-5865 2260);
DISPLAY 0.680851 (-5865 2260);
PAINT MONO (-5865 2260);
FORCEPROP 0 LASTPIN (-5875 3950) $PN 152
J 0
(-5865 3960);
DISPLAY 0.680851 (-5865 3960);
PAINT MONO (-5865 3960);
FORCEPROP 0 LASTPIN (-5875 2300) $PN 245
J 0
(-5865 2310);
DISPLAY 0.680851 (-5865 2310);
PAINT MONO (-5865 2310);
FORCEPROP 0 LASTPIN (-5875 4000) $PN 154
J 0
(-5865 4010);
DISPLAY 0.680851 (-5865 4010);
PAINT MONO (-5865 4010);
FORCEPROP 0 LASTPIN (-5875 2350) $PN 247
J 0
(-5865 2360);
DISPLAY 0.680851 (-5865 2360);
PAINT MONO (-5865 2360);
FORCEPROP 0 LASTPIN (-5875 4050) $PN 14
J 0
(-5865 4060);
DISPLAY 0.680851 (-5865 4060);
PAINT MONO (-5865 4060);
FORCEPROP 0 LASTPIN (-5875 2400) $PN 107
J 0
(-5865 2410);
DISPLAY 0.680851 (-5865 2410);
PAINT MONO (-5865 2410);
FORCEPROP 0 LASTPIN (-5875 4100) $PN 16
J 0
(-5865 4110);
DISPLAY 0.680851 (-5865 4110);
PAINT MONO (-5865 4110);
FORCEPROP 0 LASTPIN (-5875 2450) $PN 109
J 0
(-5865 2460);
DISPLAY 0.680851 (-5865 2460);
PAINT MONO (-5865 2460);
FORCEPROP 0 LASTPIN (-5875 4150) $PN 159
J 0
(-5865 4160);
DISPLAY 0.680851 (-5865 4160);
PAINT MONO (-5865 4160);
FORCEPROP 0 LASTPIN (-5875 2500) $PN 252
J 0
(-5865 2510);
DISPLAY 0.680851 (-5865 2510);
PAINT MONO (-5865 2510);
FORCEPROP 0 LASTPIN (-5875 4200) $PN 161
J 0
(-5865 4210);
DISPLAY 0.680851 (-5865 4210);
PAINT MONO (-5865 4210);
FORCEPROP 0 LASTPIN (-5875 2550) $PN 254
J 0
(-5865 2560);
DISPLAY 0.680851 (-5865 2560);
PAINT MONO (-5865 2560);
FORCEPROP 0 LASTPIN (-5875 4250) $PN 18
J 0
(-5865 4260);
DISPLAY 0.680851 (-5865 4260);
PAINT MONO (-5865 4260);
FORCEPROP 0 LASTPIN (-5875 2600) $PN 111
J 0
(-5865 2610);
DISPLAY 0.680851 (-5865 2610);
PAINT MONO (-5865 2610);
FORCEPROP 0 LASTPIN (-5875 4300) $PN 20
J 0
(-5865 4310);
DISPLAY 0.680851 (-5865 4310);
PAINT MONO (-5865 4310);
FORCEPROP 0 LASTPIN (-5875 2650) $PN 113
J 0
(-5865 2660);
DISPLAY 0.680851 (-5865 2660);
PAINT MONO (-5865 2660);
FORCEPROP 0 LASTPIN (-5875 4350) $PN 163
J 0
(-5865 4360);
DISPLAY 0.680851 (-5865 4360);
PAINT MONO (-5865 4360);
FORCEPROP 0 LASTPIN (-5875 2700) $PN 256
J 0
(-5865 2710);
DISPLAY 0.680851 (-5865 2710);
PAINT MONO (-5865 2710);
FORCEPROP 0 LASTPIN (-5875 4400) $PN 165
J 0
(-5865 4410);
DISPLAY 0.680851 (-5865 4410);
PAINT MONO (-5865 4410);
FORCEPROP 0 LASTPIN (-5875 2750) $PN 258
J 0
(-5865 2760);
DISPLAY 0.680851 (-5865 2760);
PAINT MONO (-5865 2760);
FORCEPROP 0 LASTPIN (-5875 4450) $PN 25
J 0
(-5865 4460);
DISPLAY 0.680851 (-5865 4460);
PAINT MONO (-5865 4460);
FORCEPROP 0 LASTPIN (-5875 2800) $PN 118
J 0
(-5865 2810);
DISPLAY 0.680851 (-5865 2810);
PAINT MONO (-5865 2810);
FORCEPROP 0 LASTPIN (-5875 4500) $PN 27
J 0
(-5865 4510);
DISPLAY 0.680851 (-5865 4510);
PAINT MONO (-5865 4510);
FORCEPROP 0 LASTPIN (-5875 2850) $PN 120
J 0
(-5865 2860);
DISPLAY 0.680851 (-5865 2860);
PAINT MONO (-5865 2860);
FORCEPROP 0 LASTPIN (-5875 4550) $PN 170
J 0
(-5865 4560);
DISPLAY 0.680851 (-5865 4560);
PAINT MONO (-5865 4560);
FORCEPROP 0 LASTPIN (-5875 2900) $PN 263
J 0
(-5865 2910);
DISPLAY 0.680851 (-5865 2910);
PAINT MONO (-5865 2910);
FORCEPROP 0 LASTPIN (-5875 4600) $PN 172
J 0
(-5865 4610);
DISPLAY 0.680851 (-5865 4610);
PAINT MONO (-5865 4610);
FORCEPROP 0 LASTPIN (-5875 2950) $PN 265
J 0
(-5865 2960);
DISPLAY 0.680851 (-5865 2960);
PAINT MONO (-5865 2960);
FORCEPROP 0 LASTPIN (-5875 4650) $PN 29
J 0
(-5865 4660);
DISPLAY 0.680851 (-5865 4660);
PAINT MONO (-5865 4660);
FORCEPROP 0 LASTPIN (-5875 3000) $PN 122
J 0
(-5865 3010);
DISPLAY 0.680851 (-5865 3010);
PAINT MONO (-5865 3010);
FORCEPROP 0 LASTPIN (-5875 4700) $PN 31
J 0
(-5865 4710);
DISPLAY 0.680851 (-5865 4710);
PAINT MONO (-5865 4710);
FORCEPROP 0 LASTPIN (-5875 3050) $PN 124
J 0
(-5865 3060);
DISPLAY 0.680851 (-5865 3060);
PAINT MONO (-5865 3060);
FORCEPROP 0 LASTPIN (-5875 4750) $PN 174
J 0
(-5865 4760);
DISPLAY 0.680851 (-5865 4760);
PAINT MONO (-5865 4760);
FORCEPROP 0 LASTPIN (-5875 3100) $PN 267
J 0
(-5865 3110);
DISPLAY 0.680851 (-5865 3110);
PAINT MONO (-5865 3110);
FORCEPROP 0 LASTPIN (-5875 4800) $PN 176
J 0
(-5865 4810);
DISPLAY 0.680851 (-5865 4810);
PAINT MONO (-5865 4810);
FORCEPROP 0 LASTPIN (-5875 3150) $PN 269
J 0
(-5865 3160);
DISPLAY 0.680851 (-5865 3160);
PAINT MONO (-5865 3160);
FORCEPROP 0 LASTPIN (-5875 4850) $PN 36
J 0
(-5865 4860);
DISPLAY 0.680851 (-5865 4860);
PAINT MONO (-5865 4860);
FORCEPROP 0 LASTPIN (-5875 3200) $PN 129
J 0
(-5865 3210);
DISPLAY 0.680851 (-5865 3210);
PAINT MONO (-5865 3210);
FORCEPROP 0 LASTPIN (-5875 4900) $PN 38
J 0
(-5865 4910);
DISPLAY 0.680851 (-5865 4910);
PAINT MONO (-5865 4910);
FORCEPROP 0 LASTPIN (-5875 3250) $PN 131
J 0
(-5865 3260);
DISPLAY 0.680851 (-5865 3260);
PAINT MONO (-5865 3260);
FORCEPROP 0 LASTPIN (-5875 4950) $PN 181
J 0
(-5865 4960);
DISPLAY 0.680851 (-5865 4960);
PAINT MONO (-5865 4960);
FORCEPROP 0 LASTPIN (-5875 3300) $PN 274
J 0
(-5865 3310);
DISPLAY 0.680851 (-5865 3310);
PAINT MONO (-5865 3310);
FORCEPROP 0 LASTPIN (-5875 5000) $PN 183
J 0
(-5865 5010);
DISPLAY 0.680851 (-5865 5010);
PAINT MONO (-5865 5010);
FORCEPROP 0 LASTPIN (-5875 3350) $PN 276
J 0
(-5865 3360);
DISPLAY 0.680851 (-5865 3360);
PAINT MONO (-5865 3360);
FORCEPROP 0 LASTPIN (-5875 5050) $PN 40
J 0
(-5865 5060);
DISPLAY 0.680851 (-5865 5060);
PAINT MONO (-5865 5060);
FORCEPROP 0 LASTPIN (-5875 3400) $PN 133
J 0
(-5865 3410);
DISPLAY 0.680851 (-5865 3410);
PAINT MONO (-5865 3410);
FORCEPROP 0 LASTPIN (-5875 5100) $PN 42
J 0
(-5865 5110);
DISPLAY 0.680851 (-5865 5110);
PAINT MONO (-5865 5110);
FORCEPROP 0 LASTPIN (-5875 3450) $PN 135
J 0
(-5865 3460);
DISPLAY 0.680851 (-5865 3460);
PAINT MONO (-5865 3460);
FORCEPROP 0 LASTPIN (-5875 5150) $PN 185
J 0
(-5865 5160);
DISPLAY 0.680851 (-5865 5160);
PAINT MONO (-5865 5160);
FORCEPROP 0 LASTPIN (-5875 3500) $PN 278
J 0
(-5865 3510);
DISPLAY 0.680851 (-5865 3510);
PAINT MONO (-5865 3510);
FORCEPROP 0 LASTPIN (-5875 5200) $PN 187
J 0
(-5865 5210);
DISPLAY 0.680851 (-5865 5210);
PAINT MONO (-5865 5210);
FORCEPROP 0 LASTPIN (-5875 3550) $PN 280
J 0
(-5865 3560);
DISPLAY 0.680851 (-5865 3560);
PAINT MONO (-5865 3560);
FORCEPROP 0 LASTPIN (-5875 5250) $PN 47
J 0
(-5865 5260);
DISPLAY 0.680851 (-5865 5260);
PAINT MONO (-5865 5260);
FORCEPROP 0 LASTPIN (-5875 3600) $PN 140
J 0
(-5865 3610);
DISPLAY 0.680851 (-5865 3610);
PAINT MONO (-5865 3610);
FORCEPROP 0 LASTPIN (-5875 5300) $PN 49
J 0
(-5865 5310);
DISPLAY 0.680851 (-5865 5310);
PAINT MONO (-5865 5310);
FORCEPROP 0 LASTPIN (-5875 3650) $PN 142
J 0
(-5865 3660);
DISPLAY 0.680851 (-5865 3660);
PAINT MONO (-5865 3660);
FORCEPROP 0 LASTPIN (-5875 5350) $PN 192
J 0
(-5865 5360);
DISPLAY 0.680851 (-5865 5360);
PAINT MONO (-5865 5360);
FORCEPROP 0 LASTPIN (-5875 3700) $PN 285
J 0
(-5865 3710);
DISPLAY 0.680851 (-5865 3710);
PAINT MONO (-5865 3710);
FORCEPROP 0 LASTPIN (-5875 5400) $PN 194
J 0
(-5865 5410);
DISPLAY 0.680851 (-5865 5410);
PAINT MONO (-5865 5410);
FORCEPROP 0 LASTPIN (-5875 3750) $PN 287
J 0
(-5865 3760);
DISPLAY 0.680851 (-5865 3760);
PAINT MONO (-5865 3760);
FORCEPROP 0 LASTPIN (-7075 2900) $PN 148
J 2
(-7085 2910);
DISPLAY 0.680851 (-7085 2910);
PAINT MONO (-7085 2910);
FORCEPROP 0 LASTPIN (-7075 2800) $PN 4
J 2
(-7085 2810);
DISPLAY 0.680851 (-7085 2810);
PAINT MONO (-7085 2810);
FORCEPROP 0 LASTPIN (-7075 2850) $PN 5
J 2
(-7085 2860);
DISPLAY 0.680851 (-7085 2860);
PAINT MONO (-7085 2860);
FORCEPROP 0 LASTPIN (-7075 2000) $PN 86
J 2
(-7085 2010);
DISPLAY 0.680851 (-7085 2010);
PAINT MONO (-7085 2010);
FORCEPROP 0 LASTPIN (-7075 1950) $PN 87
J 2
(-7085 1960);
DISPLAY 0.680851 (-7085 1960);
PAINT MONO (-7085 1960);
FORCEPROP 0 LASTPIN (-7075 4600) $PN 74
J 2
(-7085 4610);
DISPLAY 0.680851 (-7085 4610);
PAINT MONO (-7085 4610);
FORCEPROP 0 LASTPIN (-7075 4550) $PN 227
J 2
(-7085 4560);
DISPLAY 0.680851 (-7085 4560);
PAINT MONO (-7085 4560);
FORCEPROP 0 LASTPIN (-7075 2550) $PN 147
J 2
(-7085 2560);
DISPLAY 0.680851 (-7085 2560);
PAINT MONO (-7085 2560);
FORCEPROP 0 LASTPIN (-7075 3100) $PN 207
J 2
(-7085 3110);
DISPLAY 0.680851 (-7085 3110);
PAINT MONO (-7085 3110);
FORCEPROP 0 LASTPIN (-7075 2150) $PN 2
J 2
(-7085 2160);
DISPLAY 0.680851 (-7085 2160);
PAINT MONO (-7085 2160);
FORCEPROP 0 LASTPIN (-7075 2200) $PN 144
J 2
(-7085 2210);
DISPLAY 0.680851 (-7085 2210);
PAINT MONO (-7085 2210);
FORCEPROP 0 LASTPIN (-7075 2250) $PN 149
J 2
(-7085 2260);
DISPLAY 0.680851 (-7085 2260);
PAINT MONO (-7085 2260);
FORCEPROP 0 LASTPIN (-7075 2300) $PN 150
J 2
(-7085 2310);
DISPLAY 0.680851 (-7085 2310);
PAINT MONO (-7085 2310);
FORCEPROP 0 LASTPIN (-7075 2350) $PN 220
J 2
(-7085 2360);
DISPLAY 0.680851 (-7085 2360);
PAINT MONO (-7085 2360);
FORCEPROP 0 LASTPIN (-7075 2400) $PN 231
J 2
(-7085 2410);
DISPLAY 0.680851 (-7085 2410);
PAINT MONO (-7085 2410);
FORCEPROP 0 LASTPIN (-7075 2450) $PN 232
J 2
(-7085 2460);
DISPLAY 0.680851 (-7085 2460);
PAINT MONO (-7085 2460);
FORCEPROP 0 LASTPIN (-7075 2950) $PN 3
J 2
(-7085 2960);
DISPLAY 0.680851 (-7085 2960);
PAINT MONO (-7085 2960);
FORCEPROP 1 LAST MATERIAL IO
J 0
(-6925 5575);
DISPLAY 0.468085 (-6925 5575);
PAINT SKYBLUE (-6925 5575);
FORCEPROP 2 LAST PART_TYPE SMLF
J 0
(-6925 5825);
DISPLAY 1.021277 (-6925 5825);
FORCEPROP 2 LAST VALUE SCONN288_DDR506112002KQ
J 0
(-6925 5775);
DISPLAY 0.489362 (-6925 5775);
PAINT SKYBLUE (-6925 5775);
FORCEPROP 1 LAST CDS_LMAN_SYM_OUTLINE -450,1900,450,-1850
J 0
(-6475 3650);
DISPLAY 0.468085 (-6475 3650);
PAINT GREEN (-6475 3650);
DISPLAY INVISIBLE (-6475 3650);
FORCEPROP 1 LAST NEEDS_NO_SIZE TRUE
J 0
(-6475 3650);
DISPLAY 0.723404 (-6475 3650);
PAINT GREEN (-6475 3650);
DISPLAY INVISIBLE (-6475 3650);
FORCEPROP 2 LAST CDS_LIB pure_quanta
J 0
(-6475 3650);
DISPLAY INVISIBLE (-6475 3650);
FORCEPROP 1 LAST PATH I22
J 0
(-6475 3650);
DISPLAY 0.723404 (-6475 3650);
PAINT GREEN (-6475 3650);
DISPLAY INVISIBLE (-6475 3650);
FORCEPROP 1 LAST PART_NUMBER DFHST8FS479
J 0
(-6925 5650);
DISPLAY 0.468085 (-6925 5650);
PAINT SKYBLUE (-6925 5650);
DISPLAY INVISIBLE (-6925 5650);
FORCEADD TAP..1
(-2900 3275);
FORCEPROP 3 LASTPIN (-2950 3275) SIG_NAME M_G_CPU0_SB_DQS_DN<7>
J 0
(-2940 3285);
DISPLAY 0.659574 (-2940 3285);
PAINT MONO (-2940 3285);
DISPLAY INVISIBLE (-2940 3285);
FORCEPROP 1 LASTPIN (-2950 3275) BN 7
J 0
(-2962 3283);
DISPLAY 0.489362 (-2962 3283);
PAINT GREEN (-2962 3283);
FORCEPROP 2 LAST CDS_LIB mstr_standard
J 0
(-2900 3275);
DISPLAY 0.723404 (-2900 3275);
PAINT MONO (-2900 3275);
DISPLAY INVISIBLE (-2900 3275);
FORCEPROP 1 LAST BODY_TYPE PLUMBING
J 0
(-2900 3325);
DISPLAY 0.872340 (-2900 3325);
PAINT GREEN (-2900 3325);
DISPLAY INVISIBLE (-2900 3325);
FORCEPROP 1 LAST HDL_TAP TRUE
J 0
(-2575 3150);
DISPLAY 0.872340 (-2575 3150);
DISPLAY INVISIBLE (-2575 3150);
FORCEPROP 1 LAST PATH I220
J 0
(-2902 3275);
DISPLAY 0.872340 (-2902 3275);
PAINT GREEN (-2902 3275);
DISPLAY INVISIBLE (-2902 3275);
FORCEADD TAP..1
(-2900 3175);
FORCEPROP 3 LASTPIN (-2950 3175) SIG_NAME M_G_CPU0_SB_DQS_DN<6>
J 0
(-2940 3185);
DISPLAY 0.659574 (-2940 3185);
PAINT MONO (-2940 3185);
DISPLAY INVISIBLE (-2940 3185);
FORCEPROP 1 LASTPIN (-2950 3175) BN 6
J 0
(-2962 3183);
DISPLAY 0.489362 (-2962 3183);
PAINT GREEN (-2962 3183);
FORCEPROP 2 LAST CDS_LIB mstr_standard
J 0
(-2900 3175);
DISPLAY 0.723404 (-2900 3175);
PAINT MONO (-2900 3175);
DISPLAY INVISIBLE (-2900 3175);
FORCEPROP 1 LAST BODY_TYPE PLUMBING
J 0
(-2900 3225);
DISPLAY 0.872340 (-2900 3225);
PAINT GREEN (-2900 3225);
DISPLAY INVISIBLE (-2900 3225);
FORCEPROP 1 LAST HDL_TAP TRUE
J 0
(-2575 3050);
DISPLAY 0.872340 (-2575 3050);
DISPLAY INVISIBLE (-2575 3050);
FORCEPROP 1 LAST PATH I221
J 0
(-2902 3175);
DISPLAY 0.872340 (-2902 3175);
PAINT GREEN (-2902 3175);
DISPLAY INVISIBLE (-2902 3175);
FORCEADD TAP..1
(-2900 3075);
FORCEPROP 3 LASTPIN (-2950 3075) SIG_NAME M_G_CPU0_SB_DQS_DN<5>
J 0
(-2940 3085);
DISPLAY 0.659574 (-2940 3085);
PAINT MONO (-2940 3085);
DISPLAY INVISIBLE (-2940 3085);
FORCEPROP 1 LASTPIN (-2950 3075) BN 5
J 0
(-2962 3083);
DISPLAY 0.489362 (-2962 3083);
PAINT GREEN (-2962 3083);
FORCEPROP 2 LAST CDS_LIB mstr_standard
J 0
(-2900 3075);
DISPLAY 0.723404 (-2900 3075);
PAINT MONO (-2900 3075);
DISPLAY INVISIBLE (-2900 3075);
FORCEPROP 1 LAST BODY_TYPE PLUMBING
J 0
(-2900 3125);
DISPLAY 0.872340 (-2900 3125);
PAINT GREEN (-2900 3125);
DISPLAY INVISIBLE (-2900 3125);
FORCEPROP 1 LAST HDL_TAP TRUE
J 0
(-2575 2950);
DISPLAY 0.872340 (-2575 2950);
DISPLAY INVISIBLE (-2575 2950);
FORCEPROP 1 LAST PATH I222
J 0
(-2902 3075);
DISPLAY 0.872340 (-2902 3075);
PAINT GREEN (-2902 3075);
DISPLAY INVISIBLE (-2902 3075);
FORCEADD TAP..1
(-2900 2975);
FORCEPROP 3 LASTPIN (-2950 2975) SIG_NAME M_G_CPU0_SB_DQS_DN<4>
J 0
(-2940 2985);
DISPLAY 0.659574 (-2940 2985);
PAINT MONO (-2940 2985);
DISPLAY INVISIBLE (-2940 2985);
FORCEPROP 1 LASTPIN (-2950 2975) BN 4
J 0
(-2962 2983);
DISPLAY 0.489362 (-2962 2983);
PAINT GREEN (-2962 2983);
FORCEPROP 2 LAST CDS_LIB mstr_standard
J 0
(-2900 2975);
DISPLAY 0.723404 (-2900 2975);
PAINT MONO (-2900 2975);
DISPLAY INVISIBLE (-2900 2975);
FORCEPROP 1 LAST BODY_TYPE PLUMBING
J 0
(-2900 3025);
DISPLAY 0.872340 (-2900 3025);
PAINT GREEN (-2900 3025);
DISPLAY INVISIBLE (-2900 3025);
FORCEPROP 1 LAST HDL_TAP TRUE
J 0
(-2575 2850);
DISPLAY 0.872340 (-2575 2850);
DISPLAY INVISIBLE (-2575 2850);
FORCEPROP 1 LAST PATH I223
J 0
(-2902 2975);
DISPLAY 0.872340 (-2902 2975);
PAINT GREEN (-2902 2975);
DISPLAY INVISIBLE (-2902 2975);
FORCEADD TAP..1
(-2900 2875);
FORCEPROP 3 LASTPIN (-2950 2875) SIG_NAME M_G_CPU0_SB_DQS_DN<3>
J 0
(-2940 2885);
DISPLAY 0.659574 (-2940 2885);
PAINT MONO (-2940 2885);
DISPLAY INVISIBLE (-2940 2885);
FORCEPROP 1 LASTPIN (-2950 2875) BN 3
J 0
(-2962 2883);
DISPLAY 0.489362 (-2962 2883);
PAINT GREEN (-2962 2883);
FORCEPROP 2 LAST CDS_LIB mstr_standard
J 0
(-2900 2875);
DISPLAY 0.723404 (-2900 2875);
PAINT MONO (-2900 2875);
DISPLAY INVISIBLE (-2900 2875);
FORCEPROP 1 LAST BODY_TYPE PLUMBING
J 0
(-2900 2925);
DISPLAY 0.872340 (-2900 2925);
PAINT GREEN (-2900 2925);
DISPLAY INVISIBLE (-2900 2925);
FORCEPROP 1 LAST HDL_TAP TRUE
J 0
(-2575 2750);
DISPLAY 0.872340 (-2575 2750);
DISPLAY INVISIBLE (-2575 2750);
FORCEPROP 1 LAST PATH I224
J 0
(-2902 2875);
DISPLAY 0.872340 (-2902 2875);
PAINT GREEN (-2902 2875);
DISPLAY INVISIBLE (-2902 2875);
FORCEADD TAP..1
(-3100 3225);
FORCEPROP 3 LASTPIN (-3150 3225) SIG_NAME M_G_CPU0_SB_DQS_DP<6>
J 0
(-3140 3235);
DISPLAY 0.659574 (-3140 3235);
PAINT MONO (-3140 3235);
DISPLAY INVISIBLE (-3140 3235);
FORCEPROP 1 LASTPIN (-3150 3225) BN 6
J 0
(-3162 3233);
DISPLAY 0.489362 (-3162 3233);
PAINT GREEN (-3162 3233);
FORCEPROP 2 LAST CDS_LIB mstr_standard
J 0
(-3100 3225);
DISPLAY 0.723404 (-3100 3225);
PAINT MONO (-3100 3225);
DISPLAY INVISIBLE (-3100 3225);
FORCEPROP 1 LAST BODY_TYPE PLUMBING
J 0
(-3100 3275);
DISPLAY 0.872340 (-3100 3275);
PAINT GREEN (-3100 3275);
DISPLAY INVISIBLE (-3100 3275);
FORCEPROP 1 LAST HDL_TAP TRUE
J 0
(-2775 3100);
DISPLAY 0.872340 (-2775 3100);
DISPLAY INVISIBLE (-2775 3100);
FORCEPROP 1 LAST PATH I225
J 0
(-3102 3225);
DISPLAY 0.872340 (-3102 3225);
PAINT GREEN (-3102 3225);
DISPLAY INVISIBLE (-3102 3225);
FORCEADD TAP..1
(-3100 3325);
FORCEPROP 3 LASTPIN (-3150 3325) SIG_NAME M_G_CPU0_SB_DQS_DP<7>
J 0
(-3140 3335);
DISPLAY 0.659574 (-3140 3335);
PAINT MONO (-3140 3335);
DISPLAY INVISIBLE (-3140 3335);
FORCEPROP 1 LASTPIN (-3150 3325) BN 7
J 0
(-3162 3333);
DISPLAY 0.489362 (-3162 3333);
PAINT GREEN (-3162 3333);
FORCEPROP 2 LAST CDS_LIB mstr_standard
J 0
(-3100 3325);
DISPLAY 0.723404 (-3100 3325);
PAINT MONO (-3100 3325);
DISPLAY INVISIBLE (-3100 3325);
FORCEPROP 1 LAST BODY_TYPE PLUMBING
J 0
(-3100 3375);
DISPLAY 0.872340 (-3100 3375);
PAINT GREEN (-3100 3375);
DISPLAY INVISIBLE (-3100 3375);
FORCEPROP 1 LAST HDL_TAP TRUE
J 0
(-2775 3200);
DISPLAY 0.872340 (-2775 3200);
DISPLAY INVISIBLE (-2775 3200);
FORCEPROP 1 LAST PATH I226
J 0
(-3102 3325);
DISPLAY 0.872340 (-3102 3325);
PAINT GREEN (-3102 3325);
DISPLAY INVISIBLE (-3102 3325);
FORCEADD TAP..1
(-3100 3125);
FORCEPROP 3 LASTPIN (-3150 3125) SIG_NAME M_G_CPU0_SB_DQS_DP<5>
J 0
(-3140 3135);
DISPLAY 0.659574 (-3140 3135);
PAINT MONO (-3140 3135);
DISPLAY INVISIBLE (-3140 3135);
FORCEPROP 1 LASTPIN (-3150 3125) BN 5
J 0
(-3162 3133);
DISPLAY 0.489362 (-3162 3133);
PAINT GREEN (-3162 3133);
FORCEPROP 2 LAST CDS_LIB mstr_standard
J 0
(-3100 3125);
DISPLAY 0.723404 (-3100 3125);
PAINT MONO (-3100 3125);
DISPLAY INVISIBLE (-3100 3125);
FORCEPROP 1 LAST BODY_TYPE PLUMBING
J 0
(-3100 3175);
DISPLAY 0.872340 (-3100 3175);
PAINT GREEN (-3100 3175);
DISPLAY INVISIBLE (-3100 3175);
FORCEPROP 1 LAST HDL_TAP TRUE
J 0
(-2775 3000);
DISPLAY 0.872340 (-2775 3000);
DISPLAY INVISIBLE (-2775 3000);
FORCEPROP 1 LAST PATH I227
J 0
(-3102 3125);
DISPLAY 0.872340 (-3102 3125);
PAINT GREEN (-3102 3125);
DISPLAY INVISIBLE (-3102 3125);
FORCEADD TAP..1
(-3100 3025);
FORCEPROP 3 LASTPIN (-3150 3025) SIG_NAME M_G_CPU0_SB_DQS_DP<4>
J 0
(-3140 3035);
DISPLAY 0.659574 (-3140 3035);
PAINT MONO (-3140 3035);
DISPLAY INVISIBLE (-3140 3035);
FORCEPROP 1 LASTPIN (-3150 3025) BN 4
J 0
(-3162 3033);
DISPLAY 0.489362 (-3162 3033);
PAINT GREEN (-3162 3033);
FORCEPROP 2 LAST CDS_LIB mstr_standard
J 0
(-3100 3025);
DISPLAY 0.723404 (-3100 3025);
PAINT MONO (-3100 3025);
DISPLAY INVISIBLE (-3100 3025);
FORCEPROP 1 LAST BODY_TYPE PLUMBING
J 0
(-3100 3075);
DISPLAY 0.872340 (-3100 3075);
PAINT GREEN (-3100 3075);
DISPLAY INVISIBLE (-3100 3075);
FORCEPROP 1 LAST HDL_TAP TRUE
J 0
(-2775 2900);
DISPLAY 0.872340 (-2775 2900);
DISPLAY INVISIBLE (-2775 2900);
FORCEPROP 1 LAST PATH I228
J 0
(-3102 3025);
DISPLAY 0.872340 (-3102 3025);
PAINT GREEN (-3102 3025);
DISPLAY INVISIBLE (-3102 3025);
FORCEADD TAP..1
(-3100 2925);
FORCEPROP 3 LASTPIN (-3150 2925) SIG_NAME M_G_CPU0_SB_DQS_DP<3>
J 0
(-3140 2935);
DISPLAY 0.659574 (-3140 2935);
PAINT MONO (-3140 2935);
DISPLAY INVISIBLE (-3140 2935);
FORCEPROP 1 LASTPIN (-3150 2925) BN 3
J 0
(-3162 2933);
DISPLAY 0.489362 (-3162 2933);
PAINT GREEN (-3162 2933);
FORCEPROP 2 LAST CDS_LIB mstr_standard
J 0
(-3100 2925);
DISPLAY 0.723404 (-3100 2925);
PAINT MONO (-3100 2925);
DISPLAY INVISIBLE (-3100 2925);
FORCEPROP 1 LAST BODY_TYPE PLUMBING
J 0
(-3100 2975);
DISPLAY 0.872340 (-3100 2975);
PAINT GREEN (-3100 2975);
DISPLAY INVISIBLE (-3100 2975);
FORCEPROP 1 LAST HDL_TAP TRUE
J 0
(-2775 2800);
DISPLAY 0.872340 (-2775 2800);
DISPLAY INVISIBLE (-2775 2800);
FORCEPROP 1 LAST PATH I229
J 0
(-3102 2925);
DISPLAY 0.872340 (-3102 2925);
PAINT GREEN (-3102 2925);
DISPLAY INVISIBLE (-3102 2925);
FORCEADD TAP..1
R 2
(-7325 3200);
FORCEPROP 3 LASTPIN (-7275 3200) SIG_NAME M_G_CPU0_SB_CB<0>
J 0
(-7265 3210);
DISPLAY 0.659574 (-7265 3210);
PAINT MONO (-7265 3210);
DISPLAY INVISIBLE (-7265 3210);
FORCEPROP 1 LASTPIN (-7275 3200) BN 0
J 2
(-7263 3208);
DISPLAY 0.489362 (-7263 3208);
PAINT GREEN (-7263 3208);
FORCEPROP 2 LAST CDS_LIB mstr_standard
J 0
(-7325 3200);
DISPLAY 0.723404 (-7325 3200);
PAINT MONO (-7325 3200);
DISPLAY INVISIBLE (-7325 3200);
FORCEPROP 1 LAST BODY_TYPE PLUMBING
J 2
(-7325 3250);
DISPLAY 0.872340 (-7325 3250);
PAINT GREEN (-7325 3250);
DISPLAY INVISIBLE (-7325 3250);
FORCEPROP 1 LAST HDL_TAP TRUE
J 2
(-7650 3075);
DISPLAY 0.872340 (-7650 3075);
DISPLAY INVISIBLE (-7650 3075);
FORCEPROP 1 LAST PATH I23
J 2
(-7323 3200);
DISPLAY 0.872340 (-7323 3200);
PAINT GREEN (-7323 3200);
DISPLAY INVISIBLE (-7323 3200);
FORCEADD TAP..1
(-2900 2775);
FORCEPROP 3 LASTPIN (-2950 2775) SIG_NAME M_G_CPU0_SB_DQS_DN<2>
J 0
(-2940 2785);
DISPLAY 0.659574 (-2940 2785);
PAINT MONO (-2940 2785);
DISPLAY INVISIBLE (-2940 2785);
FORCEPROP 1 LASTPIN (-2950 2775) BN 2
J 0
(-2962 2783);
DISPLAY 0.489362 (-2962 2783);
PAINT GREEN (-2962 2783);
FORCEPROP 2 LAST CDS_LIB mstr_standard
J 0
(-2900 2775);
DISPLAY 0.723404 (-2900 2775);
PAINT MONO (-2900 2775);
DISPLAY INVISIBLE (-2900 2775);
FORCEPROP 1 LAST BODY_TYPE PLUMBING
J 0
(-2900 2825);
DISPLAY 0.872340 (-2900 2825);
PAINT GREEN (-2900 2825);
DISPLAY INVISIBLE (-2900 2825);
FORCEPROP 1 LAST HDL_TAP TRUE
J 0
(-2575 2650);
DISPLAY 0.872340 (-2575 2650);
DISPLAY INVISIBLE (-2575 2650);
FORCEPROP 1 LAST PATH I230
J 0
(-2902 2775);
DISPLAY 0.872340 (-2902 2775);
PAINT GREEN (-2902 2775);
DISPLAY INVISIBLE (-2902 2775);
FORCEADD TAP..1
(-2900 2675);
FORCEPROP 3 LASTPIN (-2950 2675) SIG_NAME M_G_CPU0_SB_DQS_DN<1>
J 0
(-2940 2685);
DISPLAY 0.659574 (-2940 2685);
PAINT MONO (-2940 2685);
DISPLAY INVISIBLE (-2940 2685);
FORCEPROP 1 LASTPIN (-2950 2675) BN 1
J 0
(-2962 2683);
DISPLAY 0.489362 (-2962 2683);
PAINT GREEN (-2962 2683);
FORCEPROP 2 LAST CDS_LIB mstr_standard
J 0
(-2900 2675);
DISPLAY 0.723404 (-2900 2675);
PAINT MONO (-2900 2675);
DISPLAY INVISIBLE (-2900 2675);
FORCEPROP 1 LAST BODY_TYPE PLUMBING
J 0
(-2900 2725);
DISPLAY 0.872340 (-2900 2725);
PAINT GREEN (-2900 2725);
DISPLAY INVISIBLE (-2900 2725);
FORCEPROP 1 LAST HDL_TAP TRUE
J 0
(-2575 2550);
DISPLAY 0.872340 (-2575 2550);
DISPLAY INVISIBLE (-2575 2550);
FORCEPROP 1 LAST PATH I231
J 0
(-2902 2675);
DISPLAY 0.872340 (-2902 2675);
PAINT GREEN (-2902 2675);
DISPLAY INVISIBLE (-2902 2675);
FORCEADD TAP..1
(-2900 2575);
FORCEPROP 3 LASTPIN (-2950 2575) SIG_NAME M_G_CPU0_SB_DQS_DN<0>
J 0
(-2940 2585);
DISPLAY 0.659574 (-2940 2585);
PAINT MONO (-2940 2585);
DISPLAY INVISIBLE (-2940 2585);
FORCEPROP 1 LASTPIN (-2950 2575) BN 0
J 0
(-2962 2583);
DISPLAY 0.489362 (-2962 2583);
PAINT GREEN (-2962 2583);
FORCEPROP 2 LAST CDS_LIB mstr_standard
J 0
(-2900 2575);
DISPLAY 0.723404 (-2900 2575);
PAINT MONO (-2900 2575);
DISPLAY INVISIBLE (-2900 2575);
FORCEPROP 1 LAST BODY_TYPE PLUMBING
J 0
(-2900 2625);
DISPLAY 0.872340 (-2900 2625);
PAINT GREEN (-2900 2625);
DISPLAY INVISIBLE (-2900 2625);
FORCEPROP 1 LAST HDL_TAP TRUE
J 0
(-2575 2450);
DISPLAY 0.872340 (-2575 2450);
DISPLAY INVISIBLE (-2575 2450);
FORCEPROP 1 LAST PATH I232
J 0
(-2902 2575);
DISPLAY 0.872340 (-2902 2575);
PAINT GREEN (-2902 2575);
DISPLAY INVISIBLE (-2902 2575);
FORCEADD TAP..1
(-3100 2625);
FORCEPROP 3 LASTPIN (-3150 2625) SIG_NAME M_G_CPU0_SB_DQS_DP<0>
J 0
(-3140 2635);
DISPLAY 0.659574 (-3140 2635);
PAINT MONO (-3140 2635);
DISPLAY INVISIBLE (-3140 2635);
FORCEPROP 1 LASTPIN (-3150 2625) BN 0
J 0
(-3162 2633);
DISPLAY 0.489362 (-3162 2633);
PAINT GREEN (-3162 2633);
FORCEPROP 2 LAST CDS_LIB mstr_standard
J 0
(-3100 2625);
DISPLAY 0.723404 (-3100 2625);
PAINT MONO (-3100 2625);
DISPLAY INVISIBLE (-3100 2625);
FORCEPROP 1 LAST BODY_TYPE PLUMBING
J 0
(-3100 2675);
DISPLAY 0.872340 (-3100 2675);
PAINT GREEN (-3100 2675);
DISPLAY INVISIBLE (-3100 2675);
FORCEPROP 1 LAST HDL_TAP TRUE
J 0
(-2775 2500);
DISPLAY 0.872340 (-2775 2500);
DISPLAY INVISIBLE (-2775 2500);
FORCEPROP 1 LAST PATH I233
J 0
(-3102 2625);
DISPLAY 0.872340 (-3102 2625);
PAINT GREEN (-3102 2625);
DISPLAY INVISIBLE (-3102 2625);
FORCEADD TAP..1
(-3100 2725);
FORCEPROP 3 LASTPIN (-3150 2725) SIG_NAME M_G_CPU0_SB_DQS_DP<1>
J 0
(-3140 2735);
DISPLAY 0.659574 (-3140 2735);
PAINT MONO (-3140 2735);
DISPLAY INVISIBLE (-3140 2735);
FORCEPROP 1 LASTPIN (-3150 2725) BN 1
J 0
(-3162 2733);
DISPLAY 0.489362 (-3162 2733);
PAINT GREEN (-3162 2733);
FORCEPROP 2 LAST CDS_LIB mstr_standard
J 0
(-3100 2725);
DISPLAY 0.723404 (-3100 2725);
PAINT MONO (-3100 2725);
DISPLAY INVISIBLE (-3100 2725);
FORCEPROP 1 LAST BODY_TYPE PLUMBING
J 0
(-3100 2775);
DISPLAY 0.872340 (-3100 2775);
PAINT GREEN (-3100 2775);
DISPLAY INVISIBLE (-3100 2775);
FORCEPROP 1 LAST HDL_TAP TRUE
J 0
(-2775 2600);
DISPLAY 0.872340 (-2775 2600);
DISPLAY INVISIBLE (-2775 2600);
FORCEPROP 1 LAST PATH I234
J 0
(-3102 2725);
DISPLAY 0.872340 (-3102 2725);
PAINT GREEN (-3102 2725);
DISPLAY INVISIBLE (-3102 2725);
FORCEADD TAP..1
(-3100 2825);
FORCEPROP 3 LASTPIN (-3150 2825) SIG_NAME M_G_CPU0_SB_DQS_DP<2>
J 0
(-3140 2835);
DISPLAY 0.659574 (-3140 2835);
PAINT MONO (-3140 2835);
DISPLAY INVISIBLE (-3140 2835);
FORCEPROP 1 LASTPIN (-3150 2825) BN 2
J 0
(-3162 2833);
DISPLAY 0.489362 (-3162 2833);
PAINT GREEN (-3162 2833);
FORCEPROP 2 LAST CDS_LIB mstr_standard
J 0
(-3100 2825);
DISPLAY 0.723404 (-3100 2825);
PAINT MONO (-3100 2825);
DISPLAY INVISIBLE (-3100 2825);
FORCEPROP 1 LAST BODY_TYPE PLUMBING
J 0
(-3100 2875);
DISPLAY 0.872340 (-3100 2875);
PAINT GREEN (-3100 2875);
DISPLAY INVISIBLE (-3100 2875);
FORCEPROP 1 LAST HDL_TAP TRUE
J 0
(-2775 2700);
DISPLAY 0.872340 (-2775 2700);
DISPLAY INVISIBLE (-2775 2700);
FORCEPROP 1 LAST PATH I235
J 0
(-3102 2825);
DISPLAY 0.872340 (-3102 2825);
PAINT GREEN (-3102 2825);
DISPLAY INVISIBLE (-3102 2825);
FORCEADD SCONN288_DDR506112002KQ..2
(-4100 3575);
FORCEPROP 1 LAST LOCATION J16
J 0
(-4700 4900);
DISPLAY 0.468085 (-4700 4900);
PAINT SKYBLUE (-4700 4900);
FORCEPROP 0 LAST $SEC 2
J 0
(-4550 5050);
DISPLAY 0.680851 (-4550 5050);
PAINT MONO (-4550 5050);
DISPLAY INVISIBLE (-4550 5050);
FORCEPROP 2 LAST CDS_SEC 2
J 0
(-4550 5050);
DISPLAY 0.680851 (-4550 5050);
DISPLAY INVISIBLE (-4550 5050);
FORCEPROP 0 LASTPIN (-3350 3625) $PN 12
J 0
(-3340 3635);
DISPLAY 0.680851 (-3340 3635);
PAINT MONO (-3340 3635);
FORCEPROP 0 LASTPIN (-3350 3675) $PN 11
J 0
(-3340 3685);
DISPLAY 0.680851 (-3340 3685);
PAINT MONO (-3340 3685);
FORCEPROP 0 LASTPIN (-3350 2575) $PN 105
J 0
(-3340 2585);
DISPLAY 0.680851 (-3340 2585);
PAINT MONO (-3340 2585);
FORCEPROP 0 LASTPIN (-3350 2625) $PN 104
J 0
(-3340 2635);
DISPLAY 0.680851 (-3340 2635);
PAINT MONO (-3340 2635);
FORCEPROP 0 LASTPIN (-3350 3725) $PN 23
J 0
(-3340 3735);
DISPLAY 0.680851 (-3340 3735);
PAINT MONO (-3340 3735);
FORCEPROP 0 LASTPIN (-3350 3775) $PN 22
J 0
(-3340 3785);
DISPLAY 0.680851 (-3340 3785);
PAINT MONO (-3340 3785);
FORCEPROP 0 LASTPIN (-3350 2675) $PN 116
J 0
(-3340 2685);
DISPLAY 0.680851 (-3340 2685);
PAINT MONO (-3340 2685);
FORCEPROP 0 LASTPIN (-3350 2725) $PN 115
J 0
(-3340 2735);
DISPLAY 0.680851 (-3340 2735);
PAINT MONO (-3340 2735);
FORCEPROP 0 LASTPIN (-3350 3825) $PN 34
J 0
(-3340 3835);
DISPLAY 0.680851 (-3340 3835);
PAINT MONO (-3340 3835);
FORCEPROP 0 LASTPIN (-3350 3875) $PN 33
J 0
(-3340 3885);
DISPLAY 0.680851 (-3340 3885);
PAINT MONO (-3340 3885);
FORCEPROP 0 LASTPIN (-3350 2775) $PN 127
J 0
(-3340 2785);
DISPLAY 0.680851 (-3340 2785);
PAINT MONO (-3340 2785);
FORCEPROP 0 LASTPIN (-3350 2825) $PN 126
J 0
(-3340 2835);
DISPLAY 0.680851 (-3340 2835);
PAINT MONO (-3340 2835);
FORCEPROP 0 LASTPIN (-3350 3925) $PN 45
J 0
(-3340 3935);
DISPLAY 0.680851 (-3340 3935);
PAINT MONO (-3340 3935);
FORCEPROP 0 LASTPIN (-3350 3975) $PN 44
J 0
(-3340 3985);
DISPLAY 0.680851 (-3340 3985);
PAINT MONO (-3340 3985);
FORCEPROP 0 LASTPIN (-3350 2875) $PN 138
J 0
(-3340 2885);
DISPLAY 0.680851 (-3340 2885);
PAINT MONO (-3340 2885);
FORCEPROP 0 LASTPIN (-3350 2925) $PN 137
J 0
(-3340 2935);
DISPLAY 0.680851 (-3340 2935);
PAINT MONO (-3340 2935);
FORCEPROP 0 LASTPIN (-3350 4025) $PN 56
J 0
(-3340 4035);
DISPLAY 0.680851 (-3340 4035);
PAINT MONO (-3340 4035);
FORCEPROP 0 LASTPIN (-3350 4075) $PN 55
J 0
(-3340 4085);
DISPLAY 0.680851 (-3340 4085);
PAINT MONO (-3340 4085);
FORCEPROP 0 LASTPIN (-3350 2975) $PN 238
J 0
(-3340 2985);
DISPLAY 0.680851 (-3340 2985);
PAINT MONO (-3340 2985);
FORCEPROP 0 LASTPIN (-3350 3025) $PN 239
J 0
(-3340 3035);
DISPLAY 0.680851 (-3340 3035);
PAINT MONO (-3340 3035);
FORCEPROP 0 LASTPIN (-3350 4125) $PN 156
J 0
(-3340 4135);
DISPLAY 0.680851 (-3340 4135);
PAINT MONO (-3340 4135);
FORCEPROP 0 LASTPIN (-3350 4175) $PN 157
J 0
(-3340 4185);
DISPLAY 0.680851 (-3340 4185);
PAINT MONO (-3340 4185);
FORCEPROP 0 LASTPIN (-3350 3075) $PN 249
J 0
(-3340 3085);
DISPLAY 0.680851 (-3340 3085);
PAINT MONO (-3340 3085);
FORCEPROP 0 LASTPIN (-3350 3125) $PN 250
J 0
(-3340 3135);
DISPLAY 0.680851 (-3340 3135);
PAINT MONO (-3340 3135);
FORCEPROP 0 LASTPIN (-3350 4225) $PN 167
J 0
(-3340 4235);
DISPLAY 0.680851 (-3340 4235);
PAINT MONO (-3340 4235);
FORCEPROP 0 LASTPIN (-3350 4275) $PN 168
J 0
(-3340 4285);
DISPLAY 0.680851 (-3340 4285);
PAINT MONO (-3340 4285);
FORCEPROP 0 LASTPIN (-3350 3175) $PN 260
J 0
(-3340 3185);
DISPLAY 0.680851 (-3340 3185);
PAINT MONO (-3340 3185);
FORCEPROP 0 LASTPIN (-3350 3225) $PN 261
J 0
(-3340 3235);
DISPLAY 0.680851 (-3340 3235);
PAINT MONO (-3340 3235);
FORCEPROP 0 LASTPIN (-3350 4325) $PN 178
J 0
(-3340 4335);
DISPLAY 0.680851 (-3340 4335);
PAINT MONO (-3340 4335);
FORCEPROP 0 LASTPIN (-3350 4375) $PN 179
J 0
(-3340 4385);
DISPLAY 0.680851 (-3340 4385);
PAINT MONO (-3340 4385);
FORCEPROP 0 LASTPIN (-3350 3275) $PN 271
J 0
(-3340 3285);
DISPLAY 0.680851 (-3340 3285);
PAINT MONO (-3340 3285);
FORCEPROP 0 LASTPIN (-3350 3325) $PN 272
J 0
(-3340 3335);
DISPLAY 0.680851 (-3340 3335);
PAINT MONO (-3340 3335);
FORCEPROP 0 LASTPIN (-3350 4425) $PN 189
J 0
(-3340 4435);
DISPLAY 0.680851 (-3340 4435);
PAINT MONO (-3340 4435);
FORCEPROP 0 LASTPIN (-3350 4475) $PN 190
J 0
(-3340 4485);
DISPLAY 0.680851 (-3340 4485);
PAINT MONO (-3340 4485);
FORCEPROP 0 LASTPIN (-3350 3375) $PN 282
J 0
(-3340 3385);
DISPLAY 0.680851 (-3340 3385);
PAINT MONO (-3340 3385);
FORCEPROP 0 LASTPIN (-3350 3425) $PN 283
J 0
(-3340 3435);
DISPLAY 0.680851 (-3340 3435);
PAINT MONO (-3340 3435);
FORCEPROP 0 LASTPIN (-3350 4525) $PN 200
J 0
(-3340 4535);
DISPLAY 0.680851 (-3340 4535);
PAINT MONO (-3340 4535);
FORCEPROP 0 LASTPIN (-3350 4575) $PN 201
J 0
(-3340 4585);
DISPLAY 0.680851 (-3340 4585);
PAINT MONO (-3340 4585);
FORCEPROP 0 LASTPIN (-3350 3475) $PN 94
J 0
(-3340 3485);
DISPLAY 0.680851 (-3340 3485);
PAINT MONO (-3340 3485);
FORCEPROP 0 LASTPIN (-3350 3525) $PN 93
J 0
(-3340 3535);
DISPLAY 0.680851 (-3340 3535);
PAINT MONO (-3340 3535);
FORCEPROP 2 LAST PART_TYPE SMLF
J 0
(-4550 5000);
DISPLAY 1.021277 (-4550 5000);
FORCEPROP 2 LAST VALUE SCONN288_DDR506112002KQ
J 0
(-4550 4950);
DISPLAY 0.489362 (-4550 4950);
PAINT SKYBLUE (-4550 4950);
FORCEPROP 1 LAST MATERIAL IO
J 0
(-4700 4750);
DISPLAY 0.468085 (-4700 4750);
PAINT SKYBLUE (-4700 4750);
FORCEPROP 1 LAST CDS_LMAN_SYM_OUTLINE -600,1150,600,-1150
J 0
(-4100 3575);
DISPLAY 0.468085 (-4100 3575);
PAINT GREEN (-4100 3575);
DISPLAY INVISIBLE (-4100 3575);
FORCEPROP 1 LAST NEEDS_NO_SIZE TRUE
J 0
(-4100 3575);
DISPLAY 0.723404 (-4100 3575);
PAINT GREEN (-4100 3575);
DISPLAY INVISIBLE (-4100 3575);
FORCEPROP 2 LAST CDS_LIB pure_quanta
J 0
(-4100 3575);
DISPLAY INVISIBLE (-4100 3575);
FORCEPROP 1 LAST PATH I236
J 0
(-4100 3575);
DISPLAY 0.723404 (-4100 3575);
PAINT GREEN (-4100 3575);
DISPLAY INVISIBLE (-4100 3575);
FORCEPROP 1 LAST PART_NUMBER DFHST8FS479
J 0
(-4700 4825);
DISPLAY 0.468085 (-4700 4825);
PAINT SKYBLUE (-4700 4825);
DISPLAY INVISIBLE (-4700 4825);
FORCEADD GND..1
(-2675 5525);
FORCEPROP 3 LASTPIN (-2675 5575) SIG_NAME GND\g
J 0
(-2665 5585);
DISPLAY 0.659574 (-2665 5585);
PAINT MONO (-2665 5585);
DISPLAY INVISIBLE (-2665 5585);
FORCEPROP 2 LAST CDS_LIB pure_quanta_power
J 0
(-2675 5525);
DISPLAY INVISIBLE (-2675 5525);
FORCEPROP 2 LAST BOM_COST MEM
J 0
(-2650 5650);
DISPLAY 0.659574 (-2650 5650);
DISPLAY INVISIBLE (-2650 5650);
FORCEPROP 1 LAST SIZE 1B
J 0
(-2600 5475);
DISPLAY 0.723404 (-2600 5475);
PAINT GREEN (-2600 5475);
DISPLAY INVISIBLE (-2600 5475);
FORCEPROP 2 LAST ROOM MEM_EFGH_DECOUPLING_CAPS
J 0
(-2650 5600);
DISPLAY 0.659574 (-2650 5600);
PAINT RED (-2650 5600);
DISPLAY INVISIBLE (-2650 5600);
FORCEPROP 1 LAST HDL_POWER GND
J 0
(-2675 5675);
DISPLAY 0.723404 (-2675 5675);
PAINT GREEN (-2675 5675);
DISPLAY INVISIBLE (-2675 5675);
FORCEPROP 1 LAST PATH I237
J 0
(-2600 5525);
DISPLAY 0.872340 (-2600 5525);
PAINT AQUA (-2600 5525);
DISPLAY INVISIBLE (-2600 5525);
FORCEADD Q_CAP..1
R 2
(-2675 5875);
FORCEPROP 1 LAST LOCATION C157
J 2
(-2725 5975);
DISPLAY 0.489362 (-2725 5975);
PAINT SKYBLUE (-2725 5975);
FORCEPROP 0 LAST $SEC 1
J 0
(-2725 6025);
DISPLAY 0.680851 (-2725 6025);
PAINT MONO (-2725 6025);
DISPLAY INVISIBLE (-2725 6025);
FORCEPROP 0 LAST CDS_SEC 1
J 0
(-2725 6025);
DISPLAY 0.680851 (-2725 6025);
DISPLAY INVISIBLE (-2725 6025);
FORCEPROP 1 LASTPIN (-2675 5975) $PN 1
J 2
(-2685 5955);
DISPLAY 0.489362 (-2685 5955);
PAINT MONO (-2685 5955);
FORCEPROP 1 LASTPIN (-2675 5775) $PN 2
J 2
(-2685 5755);
DISPLAY 0.489362 (-2685 5755);
PAINT MONO (-2685 5755);
FORCEPROP 1 LAST VALUE 10UF
J 2
(-2725 5925);
DISPLAY 0.489362 (-2725 5925);
PAINT SKYBLUE (-2725 5925);
FORCEPROP 1 LAST PACK_TYPE C0805
J 2
(-2725 5675);
DISPLAY 0.489362 (-2725 5675);
PAINT SKYBLUE (-2725 5675);
FORCEPROP 1 LAST VOLTAGE 25V
J 2
(-2725 5875);
DISPLAY 0.489362 (-2725 5875);
PAINT SKYBLUE (-2725 5875);
FORCEPROP 1 LAST TOLERANCE 10%
J 2
(-2725 5825);
DISPLAY 0.489362 (-2725 5825);
PAINT SKYBLUE (-2725 5825);
FORCEPROP 1 LAST MATERIAL X6S
J 2
(-2725 5775);
DISPLAY 0.489362 (-2725 5775);
PAINT SKYBLUE (-2725 5775);
FORCEPROP 2 LAST CDS_LIB pure_quanta
J 0
(-2675 5875);
DISPLAY INVISIBLE (-2675 5875);
FORCEPROP 0 LAST BOM_COST MEM
J 2
(-2730 6020);
DISPLAY 0.595745 (-2730 6020);
PAINT MONO (-2730 6020);
DISPLAY INVISIBLE (-2730 6020);
FORCEPROP 2 LAST ROOM 
J 2
(-2730 6020);
DISPLAY 0.595745 (-2730 6020);
PAINT RED (-2730 6020);
DISPLAY INVISIBLE (-2730 6020);
FORCEPROP 1 LAST PATH I238
J 2
(-2725 6025);
DISPLAY 0.978723 (-2725 6025);
PAINT WHITE (-2725 6025);
DISPLAY INVISIBLE (-2725 6025);
FORCEPROP 1 LAST PART_NUMBER CH6104KEA00
J 2
(-2725 5725);
DISPLAY 0.489362 (-2725 5725);
PAINT SKYBLUE (-2725 5725);
DISPLAY INVISIBLE (-2725 5725);
FORCEADD Q_CAP..1
R 2
(-2100 5875);
FORCEPROP 1 LAST LOCATION C158
J 2
(-2150 5975);
DISPLAY 0.489362 (-2150 5975);
PAINT SKYBLUE (-2150 5975);
FORCEPROP 0 LAST $SEC 1
J 0
(-2150 6025);
DISPLAY 0.680851 (-2150 6025);
PAINT MONO (-2150 6025);
DISPLAY INVISIBLE (-2150 6025);
FORCEPROP 0 LAST CDS_SEC 1
J 0
(-2150 6025);
DISPLAY 0.680851 (-2150 6025);
DISPLAY INVISIBLE (-2150 6025);
FORCEPROP 1 LASTPIN (-2100 5975) $PN 1
J 2
(-2110 5955);
DISPLAY 0.489362 (-2110 5955);
PAINT MONO (-2110 5955);
FORCEPROP 1 LASTPIN (-2100 5775) $PN 2
J 2
(-2110 5755);
DISPLAY 0.489362 (-2110 5755);
PAINT MONO (-2110 5755);
FORCEPROP 1 LAST PACK_TYPE C0805
J 2
(-2150 5675);
DISPLAY 0.489362 (-2150 5675);
PAINT SKYBLUE (-2150 5675);
FORCEPROP 1 LAST VOLTAGE 25V
J 2
(-2150 5875);
DISPLAY 0.489362 (-2150 5875);
PAINT SKYBLUE (-2150 5875);
FORCEPROP 1 LAST VALUE 10UF
J 2
(-2150 5925);
DISPLAY 0.489362 (-2150 5925);
PAINT SKYBLUE (-2150 5925);
FORCEPROP 1 LAST TOLERANCE 10%
J 2
(-2150 5825);
DISPLAY 0.489362 (-2150 5825);
PAINT SKYBLUE (-2150 5825);
FORCEPROP 1 LAST MATERIAL X6S
J 2
(-2150 5775);
DISPLAY 0.489362 (-2150 5775);
PAINT SKYBLUE (-2150 5775);
FORCEPROP 2 LAST CDS_LIB pure_quanta
J 0
(-2100 5875);
DISPLAY INVISIBLE (-2100 5875);
FORCEPROP 0 LAST BOM_COST MEM
J 2
(-2155 6020);
DISPLAY 0.595745 (-2155 6020);
PAINT MONO (-2155 6020);
DISPLAY INVISIBLE (-2155 6020);
FORCEPROP 2 LAST ROOM 
J 2
(-2155 6020);
DISPLAY 0.595745 (-2155 6020);
PAINT RED (-2155 6020);
DISPLAY INVISIBLE (-2155 6020);
FORCEPROP 1 LAST PATH I239
J 2
(-2150 6025);
DISPLAY 0.978723 (-2150 6025);
PAINT WHITE (-2150 6025);
DISPLAY INVISIBLE (-2150 6025);
FORCEPROP 1 LAST PART_NUMBER CH6104KEA00
J 2
(-2150 5725);
DISPLAY 0.489362 (-2150 5725);
PAINT SKYBLUE (-2150 5725);
DISPLAY INVISIBLE (-2150 5725);
FORCEADD TAP..1
R 2
(-7325 3250);
FORCEPROP 3 LASTPIN (-7275 3250) SIG_NAME M_G_CPU0_SB_CB<1>
J 0
(-7265 3260);
DISPLAY 0.659574 (-7265 3260);
PAINT MONO (-7265 3260);
DISPLAY INVISIBLE (-7265 3260);
FORCEPROP 1 LASTPIN (-7275 3250) BN 1
J 2
(-7263 3258);
DISPLAY 0.489362 (-7263 3258);
PAINT GREEN (-7263 3258);
FORCEPROP 2 LAST CDS_LIB mstr_standard
J 0
(-7325 3250);
DISPLAY 0.723404 (-7325 3250);
PAINT MONO (-7325 3250);
DISPLAY INVISIBLE (-7325 3250);
FORCEPROP 1 LAST BODY_TYPE PLUMBING
J 2
(-7325 3300);
DISPLAY 0.872340 (-7325 3300);
PAINT GREEN (-7325 3300);
DISPLAY INVISIBLE (-7325 3300);
FORCEPROP 1 LAST HDL_TAP TRUE
J 2
(-7650 3125);
DISPLAY 0.872340 (-7650 3125);
DISPLAY INVISIBLE (-7650 3125);
FORCEPROP 1 LAST PATH I24
J 2
(-7323 3250);
DISPLAY 0.872340 (-7323 3250);
PAINT GREEN (-7323 3250);
DISPLAY INVISIBLE (-7323 3250);
FORCEADD UNIVERSAL_POWER..1
(-2675 6200);
FORCEPROP 3 LASTPIN (-2675 6150) SIG_NAME P12V_MEM_CPU0\g
J 0
(-2665 6160);
DISPLAY 0.659574 (-2665 6160);
PAINT MONO (-2665 6160);
DISPLAY INVISIBLE (-2665 6160);
FORCEPROP 1 LAST HDL_POWER P12V_MEM_CPU0
J 1
(-2700 6250);
DISPLAY 0.489362 (-2700 6250);
PAINT GREEN (-2700 6250);
FORCEPROP 2 LAST CDS_LIB pure_quanta_power
J 0
(-2675 6200);
DISPLAY INVISIBLE (-2675 6200);
FORCEPROP 2 LAST BOM_COST VR_SYSTEM
J 0
(-2675 6300);
DISPLAY 0.617021 (-2675 6300);
PAINT PURPLE (-2675 6300);
DISPLAY INVISIBLE (-2675 6300);
FORCEPROP 1 LAST PATH I240
J 0
(-2625 6225);
DISPLAY 0.872340 (-2625 6225);
PAINT AQUA (-2625 6225);
DISPLAY INVISIBLE (-2625 6225);
FORCEADD OFFPAGE..1
(-8000 2650);
FORCEPROP 2 LAST $XR5 97 
J 0
(-8702 2650);
DISPLAY 0.638298 (-8702 2650);
PAINT MONO (-8702 2650);
FORCEPROP 2 LAST $XR4 96 
J 0
(-8612 2650);
DISPLAY 0.638298 (-8612 2650);
PAINT MONO (-8612 2650);
FORCEPROP 2 LAST $XR3 95 
J 0
(-8522 2650);
DISPLAY 0.638298 (-8522 2650);
PAINT MONO (-8522 2650);
FORCEPROP 2 LAST $XR2 94 
J 0
(-8432 2650);
DISPLAY 0.638298 (-8432 2650);
PAINT MONO (-8432 2650);
FORCEPROP 2 LAST $XR1 93 
J 0
(-8342 2650);
DISPLAY 0.638298 (-8342 2650);
PAINT MONO (-8342 2650);
FORCEPROP 2 LAST $XR0 159 
J 0
(-8252 2650);
DISPLAY 0.638298 (-8252 2650);
PAINT MONO (-8252 2650);
FORCEPROP 2 LAST CDS_LIB mstr_standard
J 0
(-8000 2650);
DISPLAY 0.808511 (-8000 2650);
DISPLAY INVISIBLE (-8000 2650);
FORCEPROP 1 LAST OFFPAGE TRUE
J 0
(-7675 2525);
DISPLAY 0.872340 (-7675 2525);
PAINT GREEN (-7675 2525);
DISPLAY INVISIBLE (-7675 2525);
FORCEPROP 1 LAST COMMENT_BODY TRUE
J 0
(-7875 2550);
DISPLAY 0.872340 (-7875 2550);
PAINT GREEN (-7875 2550);
DISPLAY INVISIBLE (-7875 2550);
FORCEPROP 2 LAST PATH I241
J 0
(-8275 2700);
DISPLAY 0.680851 (-8275 2700);
DISPLAY INVISIBLE (-8275 2700);
FORCEADD Q_RES..1
(-7375 2650);
FORCEPROP 1 LAST LOCATION R1574
J 0
(-7425 2675);
DISPLAY 0.510638 (-7425 2675);
PAINT SKYBLUE (-7425 2675);
FORCEPROP 0 LAST $SEC 1
J 0
(-7425 2750);
DISPLAY 0.680851 (-7425 2750);
PAINT MONO (-7425 2750);
DISPLAY INVISIBLE (-7425 2750);
FORCEPROP 0 LAST CDS_SEC 1
J 0
(-7425 2750);
DISPLAY 0.680851 (-7425 2750);
DISPLAY INVISIBLE (-7425 2750);
FORCEPROP 1 LASTPIN (-7475 2650) $PN 1
J 0
(-7463 2662);
DISPLAY 0.787234 (-7463 2662);
PAINT MONO (-7463 2662);
FORCEPROP 1 LASTPIN (-7275 2650) $PN 2
J 0
(-7313 2662);
DISPLAY 0.787234 (-7313 2662);
PAINT MONO (-7313 2662);
FORCEPROP 1 LAST VALUE 49.9
J 2
(-7225 2725);
DISPLAY 0.510638 (-7225 2725);
PAINT SKYBLUE (-7225 2725);
FORCEPROP 2 LAST CDS_LIB pure_quanta
J 0
(-7375 2650);
DISPLAY INVISIBLE (-7375 2650);
FORCEPROP 1 LAST MATERIAL CHIP
J 0
(-7375 2500);
DISPLAY 0.978723 (-7375 2500);
DISPLAY INVISIBLE (-7375 2500);
FORCEPROP 1 LAST PACK_TYPE 0402LF
J 0
(-7125 2500);
DISPLAY 0.978723 (-7125 2500);
DISPLAY INVISIBLE (-7125 2500);
FORCEPROP 1 LAST WATTAGE 1/16W
J 2
(-7400 2500);
DISPLAY 0.978723 (-7400 2500);
DISPLAY INVISIBLE (-7400 2500);
FORCEPROP 1 LAST TOLERANCE 1%
J 0
(-7375 2550);
DISPLAY 0.978723 (-7375 2550);
DISPLAY INVISIBLE (-7375 2550);
FORCEPROP 1 LAST PATH I242
J 0
(-7425 2800);
DISPLAY 0.978723 (-7425 2800);
PAINT WHITE (-7425 2800);
DISPLAY INVISIBLE (-7425 2800);
FORCEPROP 1 LAST PART_NUMBER CS04992FB07
J 0
(-7425 2750);
DISPLAY 0.978723 (-7425 2750);
DISPLAY INVISIBLE (-7425 2750);
FORCEADD Q_RES..2
(-8750 1300);
FORCEPROP 1 LAST LOCATION R8038
J 0
(-8705 1425);
DISPLAY 0.978723 (-8705 1425);
FORCEPROP 0 LAST $SEC 1
J 0
(-8700 1475);
DISPLAY 0.680851 (-8700 1475);
PAINT MONO (-8700 1475);
DISPLAY INVISIBLE (-8700 1475);
FORCEPROP 0 LAST CDS_SEC 1
J 0
(-8700 1475);
DISPLAY 0.680851 (-8700 1475);
DISPLAY INVISIBLE (-8700 1475);
FORCEPROP 1 LASTPIN (-8750 1400) $PN 1
J 0
(-8745 1362);
DISPLAY 0.787234 (-8745 1362);
PAINT MONO (-8745 1362);
FORCEPROP 1 LASTPIN (-8750 1200) $PN 2
J 0
(-8745 1210);
DISPLAY 0.787234 (-8745 1210);
PAINT MONO (-8745 1210);
FORCEPROP 1 LAST VALUE 10K
J 0
(-8705 1375);
DISPLAY 0.978723 (-8705 1375);
FORCEPROP 1 LAST WATTAGE 1/16W
J 0
(-8710 1275);
DISPLAY 0.978723 (-8710 1275);
FORCEPROP 1 LAST TOLERANCE 1%
J 0
(-8705 1325);
DISPLAY 0.978723 (-8705 1325);
FORCEPROP 1 LAST PACK_TYPE 0402LF
J 0
(-8710 1125);
DISPLAY 0.978723 (-8710 1125);
FORCEPROP 1 LAST MATERIAL CHIP
J 0
(-8710 1225);
DISPLAY 0.978723 (-8710 1225);
FORCEPROP 2 LAST CDS_LIB pure_quanta
J 0
(-8750 1300);
DISPLAY INVISIBLE (-8750 1300);
FORCEPROP 1 LAST PATH I243
J 0
(-8700 1475);
DISPLAY 0.978723 (-8700 1475);
PAINT WHITE (-8700 1475);
DISPLAY INVISIBLE (-8700 1475);
FORCEPROP 1 LAST PART_NUMBER CS31002FB08
J 0
(-8710 1175);
DISPLAY 0.978723 (-8710 1175);
DISPLAY INVISIBLE (-8710 1175);
FORCEADD VCC_CORE..1
(-8750 1600);
FORCEPROP 3 LASTPIN (-8750 1550) SIG_NAME P3V3_AUX\g
J 0
(-8740 1560);
DISPLAY 0.659574 (-8740 1560);
PAINT MONO (-8740 1560);
DISPLAY INVISIBLE (-8740 1560);
FORCEPROP 1 LAST HDL_POWER P3V3_AUX
J 1
(-8750 1650);
DISPLAY 0.489362 (-8750 1650);
PAINT GREEN (-8750 1650);
FORCEPROP 2 LAST ROOM PVCCINFAON_CPU0_CTRL
J 0
(-8750 1700);
DISPLAY 0.808511 (-8750 1700);
PAINT RED (-8750 1700);
DISPLAY INVISIBLE (-8750 1700);
FORCEPROP 0 LAST VOLTAGE 3.3
J 0
(-9025 1750);
DISPLAY 1.021277 (-9025 1750);
PAINT SKYBLUE (-9025 1750);
DISPLAY INVISIBLE (-9025 1750);
FORCEPROP 2 LAST CDS_LIB pure_quanta_power
J 0
(-8750 1600);
DISPLAY INVISIBLE (-8750 1600);
FORCEPROP 1 LAST PATH I244
J 0
(-8700 1625);
DISPLAY 0.872340 (-8700 1625);
PAINT AQUA (-8700 1625);
DISPLAY INVISIBLE (-8700 1625);
FORCEADD OFFPAGE..2
(-7725 900);
FORCEPROP 2 LAST $XR5 97 
J 0
(-7086 900);
DISPLAY 0.638298 (-7086 900);
PAINT MONO (-7086 900);
FORCEPROP 2 LAST $XR4 96 
J 0
(-7176 900);
DISPLAY 0.638298 (-7176 900);
PAINT MONO (-7176 900);
FORCEPROP 2 LAST $XR3 95 
J 0
(-7266 900);
DISPLAY 0.638298 (-7266 900);
PAINT MONO (-7266 900);
FORCEPROP 2 LAST $XR2 94 
J 0
(-7356 900);
DISPLAY 0.638298 (-7356 900);
PAINT MONO (-7356 900);
FORCEPROP 2 LAST $XR1 93 
J 0
(-7446 900);
DISPLAY 0.638298 (-7446 900);
PAINT MONO (-7446 900);
FORCEPROP 2 LAST $XR0 92 
J 0
(-7536 900);
DISPLAY 0.638298 (-7536 900);
PAINT MONO (-7536 900);
FORCEPROP 2 LAST CDS_LIB standard
J 0
(-7725 900);
DISPLAY INVISIBLE (-7725 900);
FORCEPROP 1 LAST OFFPAGE TRUE
J 0
(-7400 775);
DISPLAY 0.723404 (-7400 775);
PAINT GREEN (-7400 775);
DISPLAY INVISIBLE (-7400 775);
FORCEPROP 1 LAST COMMENT_BODY TRUE
J 0
(-7770 805);
DISPLAY 0.872340 (-7770 805);
PAINT GREEN (-7770 805);
DISPLAY INVISIBLE (-7770 805);
FORCEPROP 2 LAST PATH I245
J 0
(-7550 975);
DISPLAY 0.680851 (-7550 975);
DISPLAY INVISIBLE (-7550 975);
FORCEADD OFFPAGE..6
(-4250 775);
FORCEPROP 2 LAST $XR5 97 
J 0
(-4949 775);
DISPLAY 0.638298 (-4949 775);
PAINT MONO (-4949 775);
FORCEPROP 2 LAST $XR4 96 
J 0
(-4859 775);
DISPLAY 0.638298 (-4859 775);
PAINT MONO (-4859 775);
FORCEPROP 2 LAST $XR3 95 
J 0
(-4769 775);
DISPLAY 0.638298 (-4769 775);
PAINT MONO (-4769 775);
FORCEPROP 2 LAST $XR2 94 
J 0
(-4679 775);
DISPLAY 0.638298 (-4679 775);
PAINT MONO (-4679 775);
FORCEPROP 2 LAST $XR1 93 
J 0
(-4589 775);
DISPLAY 0.638298 (-4589 775);
PAINT MONO (-4589 775);
FORCEPROP 2 LAST $XR0 92 
J 0
(-4499 775);
DISPLAY 0.638298 (-4499 775);
PAINT MONO (-4499 775);
FORCEPROP 2 LAST CDS_LIB standard
J 0
(-4250 775);
DISPLAY INVISIBLE (-4250 775);
FORCEPROP 1 LAST OFFPAGE TRUE
J 0
(-3925 650);
DISPLAY 0.872340 (-3925 650);
PAINT GREEN (-3925 650);
DISPLAY INVISIBLE (-3925 650);
FORCEPROP 1 LAST COMMENT_BODY TRUE
J 0
(-4150 700);
DISPLAY 0.872340 (-4150 700);
PAINT GREEN (-4150 700);
DISPLAY INVISIBLE (-4150 700);
FORCEPROP 2 LAST PATH I246
J 0
(-4200 850);
DISPLAY 0.680851 (-4200 850);
DISPLAY INVISIBLE (-4200 850);
FORCEADD VCC_CORE..1
(-4375 1450);
FORCEPROP 3 LASTPIN (-4375 1400) SIG_NAME P3V3_AUX\g
J 0
(-4365 1410);
DISPLAY 0.659574 (-4365 1410);
PAINT MONO (-4365 1410);
DISPLAY INVISIBLE (-4365 1410);
FORCEPROP 1 LAST HDL_POWER P3V3_AUX
J 1
(-4375 1500);
DISPLAY 0.489362 (-4375 1500);
PAINT GREEN (-4375 1500);
FORCEPROP 2 LAST CDS_LIB pure_quanta_power
J 0
(-4375 1450);
DISPLAY INVISIBLE (-4375 1450);
FORCEPROP 2 LAST ROOM PVCCINFAON_CPU0_CTRL
J 0
(-4375 1550);
DISPLAY 0.808511 (-4375 1550);
PAINT RED (-4375 1550);
DISPLAY INVISIBLE (-4375 1550);
FORCEPROP 0 LAST VOLTAGE 3.3
J 0
(-4650 1600);
DISPLAY 1.021277 (-4650 1600);
PAINT SKYBLUE (-4650 1600);
DISPLAY INVISIBLE (-4650 1600);
FORCEPROP 1 LAST PATH I247
J 0
(-4325 1475);
DISPLAY 0.872340 (-4325 1475);
PAINT AQUA (-4325 1475);
DISPLAY INVISIBLE (-4325 1475);
FORCEADD Q_RES..1
(-3350 775);
FORCEPROP 1 LAST LOCATION R8083
J 0
(-3400 825);
DISPLAY 0.978723 (-3400 825);
FORCEPROP 0 LAST $SEC 1
J 0
(-3400 875);
DISPLAY 0.680851 (-3400 875);
PAINT MONO (-3400 875);
DISPLAY INVISIBLE (-3400 875);
FORCEPROP 0 LAST CDS_SEC 1
J 0
(-3400 875);
DISPLAY 0.680851 (-3400 875);
DISPLAY INVISIBLE (-3400 875);
FORCEPROP 1 LASTPIN (-3450 775) $PN 1
J 0
(-3438 787);
DISPLAY 0.787234 (-3438 787);
PAINT MONO (-3438 787);
FORCEPROP 1 LASTPIN (-3250 775) $PN 2
J 0
(-3288 787);
DISPLAY 0.787234 (-3288 787);
PAINT MONO (-3288 787);
FORCEPROP 1 LAST VALUE 0
J 2
(-3375 675);
DISPLAY 0.978723 (-3375 675);
FORCEPROP 1 LAST MATERIAL CHIP
J 0
(-3350 625);
DISPLAY 0.978723 (-3350 625);
FORCEPROP 1 LAST TOLERANCE 5%
J 0
(-3350 675);
DISPLAY 0.978723 (-3350 675);
FORCEPROP 1 LAST PACK_TYPE 0402LF
J 0
(-3100 625);
DISPLAY 0.978723 (-3100 625);
FORCEPROP 1 LAST WATTAGE 1/16W
J 2
(-3375 625);
DISPLAY 0.978723 (-3375 625);
FORCEPROP 2 LAST CDS_LIB pure_quanta
J 0
(-3350 775);
DISPLAY INVISIBLE (-3350 775);
FORCEPROP 1 LAST PATH I248
J 0
(-3400 925);
DISPLAY 0.978723 (-3400 925);
PAINT WHITE (-3400 925);
DISPLAY INVISIBLE (-3400 925);
FORCEPROP 1 LAST PART_NUMBER CS00002JB13
J 0
(-3575 575);
DISPLAY 0.978723 (-3575 575);
DISPLAY INVISIBLE (-3575 575);
FORCEADD Q_RES..1
(-3775 1250);
FORCEPROP 1 LAST LOCATION R8085
J 0
(-3825 1300);
DISPLAY 0.978723 (-3825 1300);
FORCEPROP 0 LAST $SEC 1
J 0
(-3825 1425);
DISPLAY 0.680851 (-3825 1425);
PAINT MONO (-3825 1425);
DISPLAY INVISIBLE (-3825 1425);
FORCEPROP 0 LAST CDS_SEC 1
J 0
(-3825 1425);
DISPLAY 0.680851 (-3825 1425);
DISPLAY INVISIBLE (-3825 1425);
FORCEPROP 1 LASTPIN (-3875 1250) $PN 1
J 0
(-3863 1262);
DISPLAY 0.787234 (-3863 1262);
PAINT MONO (-3863 1262);
FORCEPROP 1 LASTPIN (-3675 1250) $PN 2
J 0
(-3713 1262);
DISPLAY 0.787234 (-3713 1262);
PAINT MONO (-3713 1262);
FORCEPROP 1 LAST VALUE 10K
J 2
(-3800 1150);
DISPLAY 0.978723 (-3800 1150);
FORCEPROP 1 LAST TOLERANCE 1%
J 0
(-3775 1150);
DISPLAY 0.978723 (-3775 1150);
FORCEPROP 1 LAST MATERIAL EMPTY
J 0
(-3775 1100);
DISPLAY 0.978723 (-3775 1100);
PAINT RED (-3775 1100);
FORCEPROP 1 LAST PACK_TYPE 0402LF
J 0
(-3525 1100);
DISPLAY 0.978723 (-3525 1100);
FORCEPROP 1 LAST WATTAGE 1/16W
J 2
(-3800 1100);
DISPLAY 0.978723 (-3800 1100);
FORCEPROP 2 LAST CDS_LIB pure_quanta
J 0
(-3775 1250);
DISPLAY INVISIBLE (-3775 1250);
FORCEPROP 1 LAST PATH I249
J 0
(-3825 1400);
DISPLAY 0.978723 (-3825 1400);
PAINT WHITE (-3825 1400);
DISPLAY INVISIBLE (-3825 1400);
FORCEPROP 1 LAST PART_NUMBER CS31002FB08
J 0
(-3825 1375);
DISPLAY 0.978723 (-3825 1375);
DISPLAY INVISIBLE (-3825 1375);
FORCEADD TAP..1
R 2
(-7325 3300);
FORCEPROP 3 LASTPIN (-7275 3300) SIG_NAME M_G_CPU0_SB_CB<2>
J 0
(-7265 3310);
DISPLAY 0.659574 (-7265 3310);
PAINT MONO (-7265 3310);
DISPLAY INVISIBLE (-7265 3310);
FORCEPROP 1 LASTPIN (-7275 3300) BN 2
J 2
(-7263 3308);
DISPLAY 0.489362 (-7263 3308);
PAINT GREEN (-7263 3308);
FORCEPROP 2 LAST CDS_LIB mstr_standard
J 0
(-7325 3300);
DISPLAY 0.723404 (-7325 3300);
PAINT MONO (-7325 3300);
DISPLAY INVISIBLE (-7325 3300);
FORCEPROP 1 LAST BODY_TYPE PLUMBING
J 2
(-7325 3350);
DISPLAY 0.872340 (-7325 3350);
PAINT GREEN (-7325 3350);
DISPLAY INVISIBLE (-7325 3350);
FORCEPROP 1 LAST HDL_TAP TRUE
J 2
(-7650 3175);
DISPLAY 0.872340 (-7650 3175);
DISPLAY INVISIBLE (-7650 3175);
FORCEPROP 1 LAST PATH I25
J 2
(-7323 3300);
DISPLAY 0.872340 (-7323 3300);
PAINT GREEN (-7323 3300);
DISPLAY INVISIBLE (-7323 3300);
FORCEADD Q_RES..1
(-1925 775);
FORCEPROP 1 LAST LOCATION R8084
J 0
(-1975 825);
DISPLAY 0.978723 (-1975 825);
FORCEPROP 0 LAST $SEC 1
J 0
(-1975 875);
DISPLAY 0.680851 (-1975 875);
PAINT MONO (-1975 875);
DISPLAY INVISIBLE (-1975 875);
FORCEPROP 0 LAST CDS_SEC 1
J 0
(-1975 875);
DISPLAY 0.680851 (-1975 875);
DISPLAY INVISIBLE (-1975 875);
FORCEPROP 1 LASTPIN (-2025 775) $PN 1
J 0
(-2013 787);
DISPLAY 0.787234 (-2013 787);
PAINT MONO (-2013 787);
FORCEPROP 1 LASTPIN (-1825 775) $PN 2
J 0
(-1863 787);
DISPLAY 0.787234 (-1863 787);
PAINT MONO (-1863 787);
FORCEPROP 1 LAST WATTAGE 1/16W
J 2
(-1950 625);
DISPLAY 0.978723 (-1950 625);
FORCEPROP 1 LAST PACK_TYPE 0402LF
J 0
(-1675 625);
DISPLAY 0.978723 (-1675 625);
FORCEPROP 1 LAST MATERIAL CHIP
J 0
(-1925 625);
DISPLAY 0.978723 (-1925 625);
FORCEPROP 1 LAST TOLERANCE 5%
J 0
(-1925 675);
DISPLAY 0.978723 (-1925 675);
FORCEPROP 1 LAST VALUE 0
J 2
(-1950 675);
DISPLAY 0.978723 (-1950 675);
FORCEPROP 2 LAST CDS_LIB pure_quanta
J 0
(-1925 775);
DISPLAY INVISIBLE (-1925 775);
FORCEPROP 1 LAST PATH I250
J 0
(-1975 925);
DISPLAY 0.978723 (-1975 925);
PAINT WHITE (-1975 925);
DISPLAY INVISIBLE (-1975 925);
FORCEPROP 1 LAST PART_NUMBER CS00002JB13
J 0
(-2125 550);
DISPLAY 0.978723 (-2125 550);
DISPLAY INVISIBLE (-2125 550);
FORCEADD SCHOTTKY_12..1
(-1825 1225);
FORCEPROP 1 LAST LOCATION D8004
J 0
(-1900 1400);
DISPLAY 0.723404 (-1900 1400);
PAINT GREEN (-1900 1400);
FORCEPROP 0 LAST $SEC 1
J 0
(-1900 1550);
DISPLAY 0.680851 (-1900 1550);
PAINT MONO (-1900 1550);
DISPLAY INVISIBLE (-1900 1550);
FORCEPROP 0 LAST CDS_SEC 1
J 0
(-1900 1550);
DISPLAY 0.680851 (-1900 1550);
DISPLAY INVISIBLE (-1900 1550);
FORCEPROP 0 LASTPIN (-1950 1225) $PN 1
J 2
(-1960 1235);
DISPLAY 0.680851 (-1960 1235);
PAINT MONO (-1960 1235);
FORCEPROP 0 LASTPIN (-1700 1225) $PN 2
J 0
(-1690 1235);
DISPLAY 0.680851 (-1690 1235);
PAINT MONO (-1690 1235);
FORCEPROP 1 LAST MATERIAL EMPTY
J 0
(-1900 1300);
DISPLAY 0.723404 (-1900 1300);
PAINT RED (-1900 1300);
FORCEPROP 2 LAST VALUE B0530WS7F
J 0
(-1900 1450);
DISPLAY 0.680851 (-1900 1450);
FORCEPROP 2 LAST PART_TYPE SMLF
J 0
(-1900 1500);
DISPLAY 0.680851 (-1900 1500);
FORCEPROP 2 LAST CDS_LIB pure_quanta
J 0
(-1825 1225);
DISPLAY INVISIBLE (-1825 1225);
FORCEPROP 1 LAST CDS_LMAN_SYM_OUTLINE -75,50,75,-50
J 0
(-1825 1225);
DISPLAY 0.468085 (-1825 1225);
PAINT GREEN (-1825 1225);
DISPLAY INVISIBLE (-1825 1225);
FORCEPROP 1 LAST NEEDS_NO_SIZE TRUE
J 0
(-1750 1175);
DISPLAY 0.468085 (-1750 1175);
PAINT GREEN (-1750 1175);
DISPLAY INVISIBLE (-1750 1175);
FORCEPROP 1 LAST PATH I251
J 0
(-1825 1225);
DISPLAY 0.723404 (-1825 1225);
PAINT GREEN (-1825 1225);
DISPLAY INVISIBLE (-1825 1225);
FORCEPROP 1 LAST PART_NUMBER BC000530Z41
J 0
(-1900 1350);
DISPLAY 0.723404 (-1900 1350);
PAINT GREEN (-1900 1350);
DISPLAY INVISIBLE (-1900 1350);
FORCEADD VCC_CORE..1
(-1150 1350);
FORCEPROP 3 LASTPIN (-1150 1300) SIG_NAME P3V3_AUX\g
J 0
(-1140 1310);
DISPLAY 0.659574 (-1140 1310);
PAINT MONO (-1140 1310);
DISPLAY INVISIBLE (-1140 1310);
FORCEPROP 1 LAST HDL_POWER P3V3_AUX
J 1
(-1150 1400);
DISPLAY 0.489362 (-1150 1400);
PAINT GREEN (-1150 1400);
FORCEPROP 2 LAST CDS_LIB pure_quanta_power
J 0
(-1150 1350);
DISPLAY INVISIBLE (-1150 1350);
FORCEPROP 0 LAST VOLTAGE 3.3
J 0
(-1425 1500);
DISPLAY 1.021277 (-1425 1500);
PAINT SKYBLUE (-1425 1500);
DISPLAY INVISIBLE (-1425 1500);
FORCEPROP 2 LAST ROOM PVCCINFAON_CPU0_CTRL
J 0
(-1150 1450);
DISPLAY 0.808511 (-1150 1450);
PAINT RED (-1150 1450);
DISPLAY INVISIBLE (-1150 1450);
FORCEPROP 1 LAST PATH I252
J 0
(-1100 1375);
DISPLAY 0.872340 (-1100 1375);
PAINT AQUA (-1100 1375);
DISPLAY INVISIBLE (-1100 1375);
FORCEADD OFFPAGE..6
R 2
(-725 775);
FORCEPROP 2 LAST $XR0 82 
J 0
(-511 775);
DISPLAY 0.638298 (-511 775);
PAINT MONO (-511 775);
FORCEPROP 2 LAST CDS_LIB standard
J 0
(-725 775);
DISPLAY INVISIBLE (-725 775);
FORCEPROP 1 LAST OFFPAGE TRUE
J 2
(-1050 650);
DISPLAY 0.872340 (-1050 650);
PAINT GREEN (-1050 650);
DISPLAY INVISIBLE (-1050 650);
FORCEPROP 1 LAST COMMENT_BODY TRUE
J 2
(-825 700);
DISPLAY 0.872340 (-825 700);
PAINT GREEN (-825 700);
DISPLAY INVISIBLE (-825 700);
FORCEPROP 2 LAST PATH I253
J 0
(-525 850);
DISPLAY 0.680851 (-525 850);
DISPLAY INVISIBLE (-525 850);
FORCEADD Q_RES..1
(-7750 2850);
FORCEPROP 1 LAST LOCATION R1680
J 0
(-7950 2850);
DISPLAY 0.510638 (-7950 2850);
FORCEPROP 0 LAST $SEC 1
J 0
(-7900 2900);
DISPLAY 0.680851 (-7900 2900);
PAINT MONO (-7900 2900);
DISPLAY INVISIBLE (-7900 2900);
FORCEPROP 0 LAST CDS_SEC 1
J 0
(-7900 2900);
DISPLAY 0.680851 (-7900 2900);
DISPLAY INVISIBLE (-7900 2900);
FORCEPROP 1 LASTPIN (-7850 2850) $PN 1
J 0
(-7838 2862);
DISPLAY 0.787234 (-7838 2862);
PAINT MONO (-7838 2862);
FORCEPROP 1 LASTPIN (-7650 2850) $PN 2
J 0
(-7688 2862);
DISPLAY 0.787234 (-7688 2862);
PAINT MONO (-7688 2862);
FORCEPROP 1 LAST MATERIAL CHIP
J 0
(-7850 2825);
DISPLAY 0.404255 (-7850 2825);
FORCEPROP 1 LAST PACK_TYPE 0402LF
J 0
(-7700 2825);
DISPLAY 0.404255 (-7700 2825);
FORCEPROP 1 LAST VALUE 10
J 2
(-7600 2850);
DISPLAY 0.404255 (-7600 2850);
FORCEPROP 1 LAST TOLERANCE 1%
J 0
(-7750 2750);
DISPLAY 0.978723 (-7750 2750);
DISPLAY INVISIBLE (-7750 2750);
FORCEPROP 1 LAST WATTAGE 1/16W
J 2
(-7775 2700);
DISPLAY 0.978723 (-7775 2700);
DISPLAY INVISIBLE (-7775 2700);
FORCEPROP 2 LAST CDS_LIB pure_quanta
J 0
(-7750 2850);
DISPLAY INVISIBLE (-7750 2850);
FORCEPROP 1 LAST PATH I254
J 0
(-7800 3000);
DISPLAY 0.978723 (-7800 3000);
PAINT WHITE (-7800 3000);
DISPLAY INVISIBLE (-7800 3000);
FORCEPROP 1 LAST PART_NUMBER CS01002FB07
J 0
(-7800 2950);
DISPLAY 0.978723 (-7800 2950);
DISPLAY INVISIBLE (-7800 2950);
FORCEADD OFFPAGE..6
(-8450 2775);
FORCEPROP 2 LAST $XR5 159 
J 0
(-9179 2775);
DISPLAY 0.638298 (-9179 2775);
PAINT MONO (-9179 2775);
FORCEPROP 2 LAST $XR4 97 
J 0
(-9059 2775);
DISPLAY 0.638298 (-9059 2775);
PAINT MONO (-9059 2775);
FORCEPROP 2 LAST $XR3 96 
J 0
(-8969 2775);
DISPLAY 0.638298 (-8969 2775);
PAINT MONO (-8969 2775);
FORCEPROP 2 LAST $XR2 95 
J 0
(-8879 2775);
DISPLAY 0.638298 (-8879 2775);
PAINT MONO (-8879 2775);
FORCEPROP 2 LAST $XR1 94 
J 0
(-8789 2775);
DISPLAY 0.638298 (-8789 2775);
PAINT MONO (-8789 2775);
FORCEPROP 2 LAST $XR0 93 
J 0
(-8699 2775);
DISPLAY 0.638298 (-8699 2775);
PAINT MONO (-8699 2775);
FORCEPROP 2 LAST CDS_LIB mstr_standard
J 0
(-8450 2775);
DISPLAY 0.808511 (-8450 2775);
DISPLAY INVISIBLE (-8450 2775);
FORCEPROP 1 LAST OFFPAGE TRUE
J 0
(-8125 2650);
DISPLAY 0.872340 (-8125 2650);
PAINT GREEN (-8125 2650);
DISPLAY INVISIBLE (-8125 2650);
FORCEPROP 1 LAST COMMENT_BODY TRUE
J 0
(-8350 2700);
DISPLAY 0.872340 (-8350 2700);
PAINT GREEN (-8350 2700);
DISPLAY INVISIBLE (-8350 2700);
FORCEPROP 2 LAST PATH I255
J 0
(-8725 2825);
DISPLAY 0.680851 (-8725 2825);
DISPLAY INVISIBLE (-8725 2825);
FORCEADD TAP..1
R 2
(-7325 3350);
FORCEPROP 3 LASTPIN (-7275 3350) SIG_NAME M_G_CPU0_SB_CB<3>
J 0
(-7265 3360);
DISPLAY 0.659574 (-7265 3360);
PAINT MONO (-7265 3360);
DISPLAY INVISIBLE (-7265 3360);
FORCEPROP 1 LASTPIN (-7275 3350) BN 3
J 2
(-7263 3358);
DISPLAY 0.489362 (-7263 3358);
PAINT GREEN (-7263 3358);
FORCEPROP 2 LAST CDS_LIB mstr_standard
J 0
(-7325 3350);
DISPLAY 0.723404 (-7325 3350);
PAINT MONO (-7325 3350);
DISPLAY INVISIBLE (-7325 3350);
FORCEPROP 1 LAST BODY_TYPE PLUMBING
J 2
(-7325 3400);
DISPLAY 0.872340 (-7325 3400);
PAINT GREEN (-7325 3400);
DISPLAY INVISIBLE (-7325 3400);
FORCEPROP 1 LAST HDL_TAP TRUE
J 2
(-7650 3225);
DISPLAY 0.872340 (-7650 3225);
DISPLAY INVISIBLE (-7650 3225);
FORCEPROP 1 LAST PATH I26
J 2
(-7323 3350);
DISPLAY 0.872340 (-7323 3350);
PAINT GREEN (-7323 3350);
DISPLAY INVISIBLE (-7323 3350);
FORCEADD TAP..1
R 2
(-7325 3400);
FORCEPROP 3 LASTPIN (-7275 3400) SIG_NAME M_G_CPU0_SB_CB<4>
J 0
(-7265 3410);
DISPLAY 0.659574 (-7265 3410);
PAINT MONO (-7265 3410);
DISPLAY INVISIBLE (-7265 3410);
FORCEPROP 1 LASTPIN (-7275 3400) BN 4
J 2
(-7263 3408);
DISPLAY 0.489362 (-7263 3408);
PAINT GREEN (-7263 3408);
FORCEPROP 2 LAST CDS_LIB mstr_standard
J 0
(-7325 3400);
DISPLAY 0.723404 (-7325 3400);
PAINT MONO (-7325 3400);
DISPLAY INVISIBLE (-7325 3400);
FORCEPROP 1 LAST BODY_TYPE PLUMBING
J 2
(-7325 3450);
DISPLAY 0.872340 (-7325 3450);
PAINT GREEN (-7325 3450);
DISPLAY INVISIBLE (-7325 3450);
FORCEPROP 1 LAST HDL_TAP TRUE
J 2
(-7650 3275);
DISPLAY 0.872340 (-7650 3275);
DISPLAY INVISIBLE (-7650 3275);
FORCEPROP 1 LAST PATH I27
J 2
(-7323 3400);
DISPLAY 0.872340 (-7323 3400);
PAINT GREEN (-7323 3400);
DISPLAY INVISIBLE (-7323 3400);
FORCEADD TAP..1
R 2
(-7325 3450);
FORCEPROP 3 LASTPIN (-7275 3450) SIG_NAME M_G_CPU0_SB_CB<5>
J 0
(-7265 3460);
DISPLAY 0.659574 (-7265 3460);
PAINT MONO (-7265 3460);
DISPLAY INVISIBLE (-7265 3460);
FORCEPROP 1 LASTPIN (-7275 3450) BN 5
J 2
(-7263 3458);
DISPLAY 0.489362 (-7263 3458);
PAINT GREEN (-7263 3458);
FORCEPROP 2 LAST CDS_LIB mstr_standard
J 0
(-7325 3450);
DISPLAY 0.723404 (-7325 3450);
PAINT MONO (-7325 3450);
DISPLAY INVISIBLE (-7325 3450);
FORCEPROP 1 LAST BODY_TYPE PLUMBING
J 2
(-7325 3500);
DISPLAY 0.872340 (-7325 3500);
PAINT GREEN (-7325 3500);
DISPLAY INVISIBLE (-7325 3500);
FORCEPROP 1 LAST HDL_TAP TRUE
J 2
(-7650 3325);
DISPLAY 0.872340 (-7650 3325);
DISPLAY INVISIBLE (-7650 3325);
FORCEPROP 1 LAST PATH I28
J 2
(-7323 3450);
DISPLAY 0.872340 (-7323 3450);
PAINT GREEN (-7323 3450);
DISPLAY INVISIBLE (-7323 3450);
FORCEADD TAP..1
R 2
(-7325 3500);
FORCEPROP 3 LASTPIN (-7275 3500) SIG_NAME M_G_CPU0_SB_CB<6>
J 0
(-7265 3510);
DISPLAY 0.659574 (-7265 3510);
PAINT MONO (-7265 3510);
DISPLAY INVISIBLE (-7265 3510);
FORCEPROP 1 LASTPIN (-7275 3500) BN 6
J 2
(-7263 3508);
DISPLAY 0.489362 (-7263 3508);
PAINT GREEN (-7263 3508);
FORCEPROP 2 LAST CDS_LIB mstr_standard
J 0
(-7325 3500);
DISPLAY 0.723404 (-7325 3500);
PAINT MONO (-7325 3500);
DISPLAY INVISIBLE (-7325 3500);
FORCEPROP 1 LAST BODY_TYPE PLUMBING
J 2
(-7325 3550);
DISPLAY 0.872340 (-7325 3550);
PAINT GREEN (-7325 3550);
DISPLAY INVISIBLE (-7325 3550);
FORCEPROP 1 LAST HDL_TAP TRUE
J 2
(-7650 3375);
DISPLAY 0.872340 (-7650 3375);
DISPLAY INVISIBLE (-7650 3375);
FORCEPROP 1 LAST PATH I29
J 2
(-7323 3500);
DISPLAY 0.872340 (-7323 3500);
PAINT GREEN (-7323 3500);
DISPLAY INVISIBLE (-7323 3500);
FORCEADD TAP..1
R 2
(-7325 3550);
FORCEPROP 3 LASTPIN (-7275 3550) SIG_NAME M_G_CPU0_SB_CB<7>
J 0
(-7265 3560);
DISPLAY 0.659574 (-7265 3560);
PAINT MONO (-7265 3560);
DISPLAY INVISIBLE (-7265 3560);
FORCEPROP 1 LASTPIN (-7275 3550) BN 7
J 2
(-7263 3558);
DISPLAY 0.489362 (-7263 3558);
PAINT GREEN (-7263 3558);
FORCEPROP 2 LAST CDS_LIB mstr_standard
J 0
(-7325 3550);
DISPLAY 0.723404 (-7325 3550);
PAINT MONO (-7325 3550);
DISPLAY INVISIBLE (-7325 3550);
FORCEPROP 1 LAST BODY_TYPE PLUMBING
J 2
(-7325 3600);
DISPLAY 0.872340 (-7325 3600);
PAINT GREEN (-7325 3600);
DISPLAY INVISIBLE (-7325 3600);
FORCEPROP 1 LAST HDL_TAP TRUE
J 2
(-7650 3425);
DISPLAY 0.872340 (-7650 3425);
DISPLAY INVISIBLE (-7650 3425);
FORCEPROP 1 LAST PATH I30
J 2
(-7323 3550);
DISPLAY 0.872340 (-7323 3550);
PAINT GREEN (-7323 3550);
DISPLAY INVISIBLE (-7323 3550);
FORCEADD TAP..1
R 2
(-7325 3650);
FORCEPROP 3 LASTPIN (-7275 3650) SIG_NAME M_G_CPU0_SA_CB<0>
J 0
(-7265 3660);
DISPLAY 0.659574 (-7265 3660);
PAINT MONO (-7265 3660);
DISPLAY INVISIBLE (-7265 3660);
FORCEPROP 1 LASTPIN (-7275 3650) BN 0
J 2
(-7263 3658);
DISPLAY 0.489362 (-7263 3658);
PAINT GREEN (-7263 3658);
FORCEPROP 2 LAST CDS_LIB mstr_standard
J 0
(-7325 3650);
DISPLAY 0.723404 (-7325 3650);
PAINT MONO (-7325 3650);
DISPLAY INVISIBLE (-7325 3650);
FORCEPROP 1 LAST BODY_TYPE PLUMBING
J 2
(-7325 3700);
DISPLAY 0.872340 (-7325 3700);
PAINT GREEN (-7325 3700);
DISPLAY INVISIBLE (-7325 3700);
FORCEPROP 1 LAST HDL_TAP TRUE
J 2
(-7650 3525);
DISPLAY 0.872340 (-7650 3525);
DISPLAY INVISIBLE (-7650 3525);
FORCEPROP 1 LAST PATH I31
J 2
(-7323 3650);
DISPLAY 0.872340 (-7323 3650);
PAINT GREEN (-7323 3650);
DISPLAY INVISIBLE (-7323 3650);
FORCEADD TAP..1
R 2
(-7325 3700);
FORCEPROP 3 LASTPIN (-7275 3700) SIG_NAME M_G_CPU0_SA_CB<1>
J 0
(-7265 3710);
DISPLAY 0.659574 (-7265 3710);
PAINT MONO (-7265 3710);
DISPLAY INVISIBLE (-7265 3710);
FORCEPROP 1 LASTPIN (-7275 3700) BN 1
J 2
(-7263 3708);
DISPLAY 0.489362 (-7263 3708);
PAINT GREEN (-7263 3708);
FORCEPROP 2 LAST CDS_LIB mstr_standard
J 0
(-7325 3700);
DISPLAY 0.723404 (-7325 3700);
PAINT MONO (-7325 3700);
DISPLAY INVISIBLE (-7325 3700);
FORCEPROP 1 LAST BODY_TYPE PLUMBING
J 2
(-7325 3750);
DISPLAY 0.872340 (-7325 3750);
PAINT GREEN (-7325 3750);
DISPLAY INVISIBLE (-7325 3750);
FORCEPROP 1 LAST HDL_TAP TRUE
J 2
(-7650 3575);
DISPLAY 0.872340 (-7650 3575);
DISPLAY INVISIBLE (-7650 3575);
FORCEPROP 1 LAST PATH I32
J 2
(-7323 3700);
DISPLAY 0.872340 (-7323 3700);
PAINT GREEN (-7323 3700);
DISPLAY INVISIBLE (-7323 3700);
FORCEADD TAP..1
R 2
(-7325 3750);
FORCEPROP 3 LASTPIN (-7275 3750) SIG_NAME M_G_CPU0_SA_CB<2>
J 0
(-7265 3760);
DISPLAY 0.659574 (-7265 3760);
PAINT MONO (-7265 3760);
DISPLAY INVISIBLE (-7265 3760);
FORCEPROP 1 LASTPIN (-7275 3750) BN 2
J 2
(-7263 3758);
DISPLAY 0.489362 (-7263 3758);
PAINT GREEN (-7263 3758);
FORCEPROP 2 LAST CDS_LIB mstr_standard
J 0
(-7325 3750);
DISPLAY 0.723404 (-7325 3750);
PAINT MONO (-7325 3750);
DISPLAY INVISIBLE (-7325 3750);
FORCEPROP 1 LAST BODY_TYPE PLUMBING
J 2
(-7325 3800);
DISPLAY 0.872340 (-7325 3800);
PAINT GREEN (-7325 3800);
DISPLAY INVISIBLE (-7325 3800);
FORCEPROP 1 LAST HDL_TAP TRUE
J 2
(-7650 3625);
DISPLAY 0.872340 (-7650 3625);
DISPLAY INVISIBLE (-7650 3625);
FORCEPROP 1 LAST PATH I33
J 2
(-7323 3750);
DISPLAY 0.872340 (-7323 3750);
PAINT GREEN (-7323 3750);
DISPLAY INVISIBLE (-7323 3750);
FORCEADD TAP..1
R 2
(-7325 3800);
FORCEPROP 3 LASTPIN (-7275 3800) SIG_NAME M_G_CPU0_SA_CB<3>
J 0
(-7265 3810);
DISPLAY 0.659574 (-7265 3810);
PAINT MONO (-7265 3810);
DISPLAY INVISIBLE (-7265 3810);
FORCEPROP 1 LASTPIN (-7275 3800) BN 3
J 2
(-7263 3808);
DISPLAY 0.489362 (-7263 3808);
PAINT GREEN (-7263 3808);
FORCEPROP 2 LAST CDS_LIB mstr_standard
J 0
(-7325 3800);
DISPLAY 0.723404 (-7325 3800);
PAINT MONO (-7325 3800);
DISPLAY INVISIBLE (-7325 3800);
FORCEPROP 1 LAST BODY_TYPE PLUMBING
J 2
(-7325 3850);
DISPLAY 0.872340 (-7325 3850);
PAINT GREEN (-7325 3850);
DISPLAY INVISIBLE (-7325 3850);
FORCEPROP 1 LAST HDL_TAP TRUE
J 2
(-7650 3675);
DISPLAY 0.872340 (-7650 3675);
DISPLAY INVISIBLE (-7650 3675);
FORCEPROP 1 LAST PATH I34
J 2
(-7323 3800);
DISPLAY 0.872340 (-7323 3800);
PAINT GREEN (-7323 3800);
DISPLAY INVISIBLE (-7323 3800);
FORCEADD TAP..1
R 2
(-7325 3850);
FORCEPROP 3 LASTPIN (-7275 3850) SIG_NAME M_G_CPU0_SA_CB<4>
J 0
(-7265 3860);
DISPLAY 0.659574 (-7265 3860);
PAINT MONO (-7265 3860);
DISPLAY INVISIBLE (-7265 3860);
FORCEPROP 1 LASTPIN (-7275 3850) BN 4
J 2
(-7263 3858);
DISPLAY 0.489362 (-7263 3858);
PAINT GREEN (-7263 3858);
FORCEPROP 2 LAST CDS_LIB mstr_standard
J 0
(-7325 3850);
DISPLAY 0.723404 (-7325 3850);
PAINT MONO (-7325 3850);
DISPLAY INVISIBLE (-7325 3850);
FORCEPROP 1 LAST BODY_TYPE PLUMBING
J 2
(-7325 3900);
DISPLAY 0.872340 (-7325 3900);
PAINT GREEN (-7325 3900);
DISPLAY INVISIBLE (-7325 3900);
FORCEPROP 1 LAST HDL_TAP TRUE
J 2
(-7650 3725);
DISPLAY 0.872340 (-7650 3725);
DISPLAY INVISIBLE (-7650 3725);
FORCEPROP 1 LAST PATH I35
J 2
(-7323 3850);
DISPLAY 0.872340 (-7323 3850);
PAINT GREEN (-7323 3850);
DISPLAY INVISIBLE (-7323 3850);
FORCEADD TAP..1
R 2
(-7325 3900);
FORCEPROP 3 LASTPIN (-7275 3900) SIG_NAME M_G_CPU0_SA_CB<5>
J 0
(-7265 3910);
DISPLAY 0.659574 (-7265 3910);
PAINT MONO (-7265 3910);
DISPLAY INVISIBLE (-7265 3910);
FORCEPROP 1 LASTPIN (-7275 3900) BN 5
J 2
(-7263 3908);
DISPLAY 0.489362 (-7263 3908);
PAINT GREEN (-7263 3908);
FORCEPROP 2 LAST CDS_LIB mstr_standard
J 0
(-7325 3900);
DISPLAY 0.723404 (-7325 3900);
PAINT MONO (-7325 3900);
DISPLAY INVISIBLE (-7325 3900);
FORCEPROP 1 LAST BODY_TYPE PLUMBING
J 2
(-7325 3950);
DISPLAY 0.872340 (-7325 3950);
PAINT GREEN (-7325 3950);
DISPLAY INVISIBLE (-7325 3950);
FORCEPROP 1 LAST HDL_TAP TRUE
J 2
(-7650 3775);
DISPLAY 0.872340 (-7650 3775);
DISPLAY INVISIBLE (-7650 3775);
FORCEPROP 1 LAST PATH I36
J 2
(-7323 3900);
DISPLAY 0.872340 (-7323 3900);
PAINT GREEN (-7323 3900);
DISPLAY INVISIBLE (-7323 3900);
FORCEADD TAP..1
R 2
(-7325 3950);
FORCEPROP 3 LASTPIN (-7275 3950) SIG_NAME M_G_CPU0_SA_CB<6>
J 0
(-7265 3960);
DISPLAY 0.659574 (-7265 3960);
PAINT MONO (-7265 3960);
DISPLAY INVISIBLE (-7265 3960);
FORCEPROP 1 LASTPIN (-7275 3950) BN 6
J 2
(-7263 3958);
DISPLAY 0.489362 (-7263 3958);
PAINT GREEN (-7263 3958);
FORCEPROP 2 LAST CDS_LIB mstr_standard
J 0
(-7325 3950);
DISPLAY 0.723404 (-7325 3950);
PAINT MONO (-7325 3950);
DISPLAY INVISIBLE (-7325 3950);
FORCEPROP 1 LAST BODY_TYPE PLUMBING
J 2
(-7325 4000);
DISPLAY 0.872340 (-7325 4000);
PAINT GREEN (-7325 4000);
DISPLAY INVISIBLE (-7325 4000);
FORCEPROP 1 LAST HDL_TAP TRUE
J 2
(-7650 3825);
DISPLAY 0.872340 (-7650 3825);
DISPLAY INVISIBLE (-7650 3825);
FORCEPROP 1 LAST PATH I37
J 2
(-7323 3950);
DISPLAY 0.872340 (-7323 3950);
PAINT GREEN (-7323 3950);
DISPLAY INVISIBLE (-7323 3950);
FORCEADD TAP..1
R 2
(-7325 4000);
FORCEPROP 3 LASTPIN (-7275 4000) SIG_NAME M_G_CPU0_SA_CB<7>
J 0
(-7265 4010);
DISPLAY 0.659574 (-7265 4010);
PAINT MONO (-7265 4010);
DISPLAY INVISIBLE (-7265 4010);
FORCEPROP 1 LASTPIN (-7275 4000) BN 7
J 2
(-7263 4008);
DISPLAY 0.489362 (-7263 4008);
PAINT GREEN (-7263 4008);
FORCEPROP 2 LAST CDS_LIB mstr_standard
J 0
(-7325 4000);
DISPLAY 0.723404 (-7325 4000);
PAINT MONO (-7325 4000);
DISPLAY INVISIBLE (-7325 4000);
FORCEPROP 1 LAST BODY_TYPE PLUMBING
J 2
(-7325 4050);
DISPLAY 0.872340 (-7325 4050);
PAINT GREEN (-7325 4050);
DISPLAY INVISIBLE (-7325 4050);
FORCEPROP 1 LAST HDL_TAP TRUE
J 2
(-7650 3875);
DISPLAY 0.872340 (-7650 3875);
DISPLAY INVISIBLE (-7650 3875);
FORCEPROP 1 LAST PATH I38
J 2
(-7323 4000);
DISPLAY 0.872340 (-7323 4000);
PAINT GREEN (-7323 4000);
DISPLAY INVISIBLE (-7323 4000);
FORCEADD TAP..1
(-5625 2250);
FORCEPROP 3 LASTPIN (-5675 2250) SIG_NAME M_G_CPU0_SB_DQ<1>
J 0
(-5665 2260);
DISPLAY 0.659574 (-5665 2260);
PAINT MONO (-5665 2260);
DISPLAY INVISIBLE (-5665 2260);
FORCEPROP 1 LASTPIN (-5675 2250) BN 1
J 0
(-5687 2258);
DISPLAY 0.489362 (-5687 2258);
PAINT GREEN (-5687 2258);
FORCEPROP 2 LAST CDS_LIB mstr_standard
J 0
(-5625 2250);
DISPLAY 0.723404 (-5625 2250);
PAINT MONO (-5625 2250);
DISPLAY INVISIBLE (-5625 2250);
FORCEPROP 1 LAST BODY_TYPE PLUMBING
J 0
(-5625 2300);
DISPLAY 0.872340 (-5625 2300);
PAINT GREEN (-5625 2300);
DISPLAY INVISIBLE (-5625 2300);
FORCEPROP 1 LAST HDL_TAP TRUE
J 0
(-5300 2125);
DISPLAY 0.872340 (-5300 2125);
DISPLAY INVISIBLE (-5300 2125);
FORCEPROP 1 LAST PATH I46
J 0
(-5627 2250);
DISPLAY 0.872340 (-5627 2250);
PAINT GREEN (-5627 2250);
DISPLAY INVISIBLE (-5627 2250);
FORCEADD TAP..1
(-5625 2200);
FORCEPROP 3 LASTPIN (-5675 2200) SIG_NAME M_G_CPU0_SB_DQ<0>
J 0
(-5665 2210);
DISPLAY 0.659574 (-5665 2210);
PAINT MONO (-5665 2210);
DISPLAY INVISIBLE (-5665 2210);
FORCEPROP 1 LASTPIN (-5675 2200) BN 0
J 0
(-5687 2208);
DISPLAY 0.489362 (-5687 2208);
PAINT GREEN (-5687 2208);
FORCEPROP 2 LAST CDS_LIB mstr_standard
J 0
(-5625 2200);
DISPLAY 0.723404 (-5625 2200);
PAINT MONO (-5625 2200);
DISPLAY INVISIBLE (-5625 2200);
FORCEPROP 1 LAST BODY_TYPE PLUMBING
J 0
(-5625 2250);
DISPLAY 0.872340 (-5625 2250);
PAINT GREEN (-5625 2250);
DISPLAY INVISIBLE (-5625 2250);
FORCEPROP 1 LAST HDL_TAP TRUE
J 0
(-5300 2075);
DISPLAY 0.872340 (-5300 2075);
DISPLAY INVISIBLE (-5300 2075);
FORCEPROP 1 LAST PATH I47
J 0
(-5627 2200);
DISPLAY 0.872340 (-5627 2200);
PAINT GREEN (-5627 2200);
DISPLAY INVISIBLE (-5627 2200);
FORCEADD TAP..1
(-5625 2400);
FORCEPROP 3 LASTPIN (-5675 2400) SIG_NAME M_G_CPU0_SB_DQ<4>
J 0
(-5665 2410);
DISPLAY 0.659574 (-5665 2410);
PAINT MONO (-5665 2410);
DISPLAY INVISIBLE (-5665 2410);
FORCEPROP 1 LASTPIN (-5675 2400) BN 4
J 0
(-5687 2408);
DISPLAY 0.489362 (-5687 2408);
PAINT GREEN (-5687 2408);
FORCEPROP 2 LAST CDS_LIB mstr_standard
J 0
(-5625 2400);
DISPLAY 0.723404 (-5625 2400);
PAINT MONO (-5625 2400);
DISPLAY INVISIBLE (-5625 2400);
FORCEPROP 1 LAST BODY_TYPE PLUMBING
J 0
(-5625 2450);
DISPLAY 0.872340 (-5625 2450);
PAINT GREEN (-5625 2450);
DISPLAY INVISIBLE (-5625 2450);
FORCEPROP 1 LAST HDL_TAP TRUE
J 0
(-5300 2275);
DISPLAY 0.872340 (-5300 2275);
DISPLAY INVISIBLE (-5300 2275);
FORCEPROP 1 LAST PATH I48
J 0
(-5627 2400);
DISPLAY 0.872340 (-5627 2400);
PAINT GREEN (-5627 2400);
DISPLAY INVISIBLE (-5627 2400);
FORCEADD TAP..1
(-5625 2350);
FORCEPROP 3 LASTPIN (-5675 2350) SIG_NAME M_G_CPU0_SB_DQ<3>
J 0
(-5665 2360);
DISPLAY 0.659574 (-5665 2360);
PAINT MONO (-5665 2360);
DISPLAY INVISIBLE (-5665 2360);
FORCEPROP 1 LASTPIN (-5675 2350) BN 3
J 0
(-5687 2358);
DISPLAY 0.489362 (-5687 2358);
PAINT GREEN (-5687 2358);
FORCEPROP 2 LAST CDS_LIB mstr_standard
J 0
(-5625 2350);
DISPLAY 0.723404 (-5625 2350);
PAINT MONO (-5625 2350);
DISPLAY INVISIBLE (-5625 2350);
FORCEPROP 1 LAST BODY_TYPE PLUMBING
J 0
(-5625 2400);
DISPLAY 0.872340 (-5625 2400);
PAINT GREEN (-5625 2400);
DISPLAY INVISIBLE (-5625 2400);
FORCEPROP 1 LAST HDL_TAP TRUE
J 0
(-5300 2225);
DISPLAY 0.872340 (-5300 2225);
DISPLAY INVISIBLE (-5300 2225);
FORCEPROP 1 LAST PATH I49
J 0
(-5627 2350);
DISPLAY 0.872340 (-5627 2350);
PAINT GREEN (-5627 2350);
DISPLAY INVISIBLE (-5627 2350);
FORCEADD TAP..1
(-5625 2300);
FORCEPROP 3 LASTPIN (-5675 2300) SIG_NAME M_G_CPU0_SB_DQ<2>
J 0
(-5665 2310);
DISPLAY 0.659574 (-5665 2310);
PAINT MONO (-5665 2310);
DISPLAY INVISIBLE (-5665 2310);
FORCEPROP 1 LASTPIN (-5675 2300) BN 2
J 0
(-5687 2308);
DISPLAY 0.489362 (-5687 2308);
PAINT GREEN (-5687 2308);
FORCEPROP 2 LAST CDS_LIB mstr_standard
J 0
(-5625 2300);
DISPLAY 0.723404 (-5625 2300);
PAINT MONO (-5625 2300);
DISPLAY INVISIBLE (-5625 2300);
FORCEPROP 1 LAST BODY_TYPE PLUMBING
J 0
(-5625 2350);
DISPLAY 0.872340 (-5625 2350);
PAINT GREEN (-5625 2350);
DISPLAY INVISIBLE (-5625 2350);
FORCEPROP 1 LAST HDL_TAP TRUE
J 0
(-5300 2175);
DISPLAY 0.872340 (-5300 2175);
DISPLAY INVISIBLE (-5300 2175);
FORCEPROP 1 LAST PATH I50
J 0
(-5627 2300);
DISPLAY 0.872340 (-5627 2300);
PAINT GREEN (-5627 2300);
DISPLAY INVISIBLE (-5627 2300);
FORCEADD TAP..1
(-5625 2450);
FORCEPROP 3 LASTPIN (-5675 2450) SIG_NAME M_G_CPU0_SB_DQ<5>
J 0
(-5665 2460);
DISPLAY 0.659574 (-5665 2460);
PAINT MONO (-5665 2460);
DISPLAY INVISIBLE (-5665 2460);
FORCEPROP 1 LASTPIN (-5675 2450) BN 5
J 0
(-5687 2458);
DISPLAY 0.489362 (-5687 2458);
PAINT GREEN (-5687 2458);
FORCEPROP 2 LAST CDS_LIB mstr_standard
J 0
(-5625 2450);
DISPLAY 0.723404 (-5625 2450);
PAINT MONO (-5625 2450);
DISPLAY INVISIBLE (-5625 2450);
FORCEPROP 1 LAST BODY_TYPE PLUMBING
J 0
(-5625 2500);
DISPLAY 0.872340 (-5625 2500);
PAINT GREEN (-5625 2500);
DISPLAY INVISIBLE (-5625 2500);
FORCEPROP 1 LAST HDL_TAP TRUE
J 0
(-5300 2325);
DISPLAY 0.872340 (-5300 2325);
DISPLAY INVISIBLE (-5300 2325);
FORCEPROP 1 LAST PATH I51
J 0
(-5627 2450);
DISPLAY 0.872340 (-5627 2450);
PAINT GREEN (-5627 2450);
DISPLAY INVISIBLE (-5627 2450);
FORCEADD TAP..1
(-5625 2500);
FORCEPROP 3 LASTPIN (-5675 2500) SIG_NAME M_G_CPU0_SB_DQ<6>
J 0
(-5665 2510);
DISPLAY 0.659574 (-5665 2510);
PAINT MONO (-5665 2510);
DISPLAY INVISIBLE (-5665 2510);
FORCEPROP 1 LASTPIN (-5675 2500) BN 6
J 0
(-5687 2508);
DISPLAY 0.489362 (-5687 2508);
PAINT GREEN (-5687 2508);
FORCEPROP 2 LAST CDS_LIB mstr_standard
J 0
(-5625 2500);
DISPLAY 0.723404 (-5625 2500);
PAINT MONO (-5625 2500);
DISPLAY INVISIBLE (-5625 2500);
FORCEPROP 1 LAST BODY_TYPE PLUMBING
J 0
(-5625 2550);
DISPLAY 0.872340 (-5625 2550);
PAINT GREEN (-5625 2550);
DISPLAY INVISIBLE (-5625 2550);
FORCEPROP 1 LAST HDL_TAP TRUE
J 0
(-5300 2375);
DISPLAY 0.872340 (-5300 2375);
DISPLAY INVISIBLE (-5300 2375);
FORCEPROP 1 LAST PATH I52
J 0
(-5627 2500);
DISPLAY 0.872340 (-5627 2500);
PAINT GREEN (-5627 2500);
DISPLAY INVISIBLE (-5627 2500);
FORCEADD TAP..1
(-5625 2650);
FORCEPROP 3 LASTPIN (-5675 2650) SIG_NAME M_G_CPU0_SB_DQ<9>
J 0
(-5665 2660);
DISPLAY 0.659574 (-5665 2660);
PAINT MONO (-5665 2660);
DISPLAY INVISIBLE (-5665 2660);
FORCEPROP 1 LASTPIN (-5675 2650) BN 9
J 0
(-5687 2658);
DISPLAY 0.489362 (-5687 2658);
PAINT GREEN (-5687 2658);
FORCEPROP 2 LAST CDS_LIB mstr_standard
J 0
(-5625 2650);
DISPLAY 0.723404 (-5625 2650);
PAINT MONO (-5625 2650);
DISPLAY INVISIBLE (-5625 2650);
FORCEPROP 1 LAST BODY_TYPE PLUMBING
J 0
(-5625 2700);
DISPLAY 0.872340 (-5625 2700);
PAINT GREEN (-5625 2700);
DISPLAY INVISIBLE (-5625 2700);
FORCEPROP 1 LAST HDL_TAP TRUE
J 0
(-5300 2525);
DISPLAY 0.872340 (-5300 2525);
DISPLAY INVISIBLE (-5300 2525);
FORCEPROP 1 LAST PATH I53
J 0
(-5627 2650);
DISPLAY 0.872340 (-5627 2650);
PAINT GREEN (-5627 2650);
DISPLAY INVISIBLE (-5627 2650);
FORCEADD TAP..1
(-5625 2600);
FORCEPROP 3 LASTPIN (-5675 2600) SIG_NAME M_G_CPU0_SB_DQ<8>
J 0
(-5665 2610);
DISPLAY 0.659574 (-5665 2610);
PAINT MONO (-5665 2610);
DISPLAY INVISIBLE (-5665 2610);
FORCEPROP 1 LASTPIN (-5675 2600) BN 8
J 0
(-5687 2608);
DISPLAY 0.489362 (-5687 2608);
PAINT GREEN (-5687 2608);
FORCEPROP 2 LAST CDS_LIB mstr_standard
J 0
(-5625 2600);
DISPLAY 0.723404 (-5625 2600);
PAINT MONO (-5625 2600);
DISPLAY INVISIBLE (-5625 2600);
FORCEPROP 1 LAST BODY_TYPE PLUMBING
J 0
(-5625 2650);
DISPLAY 0.872340 (-5625 2650);
PAINT GREEN (-5625 2650);
DISPLAY INVISIBLE (-5625 2650);
FORCEPROP 1 LAST HDL_TAP TRUE
J 0
(-5300 2475);
DISPLAY 0.872340 (-5300 2475);
DISPLAY INVISIBLE (-5300 2475);
FORCEPROP 1 LAST PATH I54
J 0
(-5627 2600);
DISPLAY 0.872340 (-5627 2600);
PAINT GREEN (-5627 2600);
DISPLAY INVISIBLE (-5627 2600);
FORCEADD TAP..1
(-5625 2550);
FORCEPROP 3 LASTPIN (-5675 2550) SIG_NAME M_G_CPU0_SB_DQ<7>
J 0
(-5665 2560);
DISPLAY 0.659574 (-5665 2560);
PAINT MONO (-5665 2560);
DISPLAY INVISIBLE (-5665 2560);
FORCEPROP 1 LASTPIN (-5675 2550) BN 7
J 0
(-5687 2558);
DISPLAY 0.489362 (-5687 2558);
PAINT GREEN (-5687 2558);
FORCEPROP 2 LAST CDS_LIB mstr_standard
J 0
(-5625 2550);
DISPLAY 0.723404 (-5625 2550);
PAINT MONO (-5625 2550);
DISPLAY INVISIBLE (-5625 2550);
FORCEPROP 1 LAST BODY_TYPE PLUMBING
J 0
(-5625 2600);
DISPLAY 0.872340 (-5625 2600);
PAINT GREEN (-5625 2600);
DISPLAY INVISIBLE (-5625 2600);
FORCEPROP 1 LAST HDL_TAP TRUE
J 0
(-5300 2425);
DISPLAY 0.872340 (-5300 2425);
DISPLAY INVISIBLE (-5300 2425);
FORCEPROP 1 LAST PATH I55
J 0
(-5627 2550);
DISPLAY 0.872340 (-5627 2550);
PAINT GREEN (-5627 2550);
DISPLAY INVISIBLE (-5627 2550);
FORCEADD TAP..1
(-5625 2700);
FORCEPROP 3 LASTPIN (-5675 2700) SIG_NAME M_G_CPU0_SB_DQ<10>
J 0
(-5665 2710);
DISPLAY 0.659574 (-5665 2710);
PAINT MONO (-5665 2710);
DISPLAY INVISIBLE (-5665 2710);
FORCEPROP 1 LASTPIN (-5675 2700) BN 10
J 0
(-5687 2708);
DISPLAY 0.489362 (-5687 2708);
PAINT GREEN (-5687 2708);
FORCEPROP 2 LAST CDS_LIB mstr_standard
J 0
(-5625 2700);
DISPLAY 0.723404 (-5625 2700);
PAINT MONO (-5625 2700);
DISPLAY INVISIBLE (-5625 2700);
FORCEPROP 1 LAST BODY_TYPE PLUMBING
J 0
(-5625 2750);
DISPLAY 0.872340 (-5625 2750);
PAINT GREEN (-5625 2750);
DISPLAY INVISIBLE (-5625 2750);
FORCEPROP 1 LAST HDL_TAP TRUE
J 0
(-5300 2575);
DISPLAY 0.872340 (-5300 2575);
DISPLAY INVISIBLE (-5300 2575);
FORCEPROP 1 LAST PATH I56
J 0
(-5627 2700);
DISPLAY 0.872340 (-5627 2700);
PAINT GREEN (-5627 2700);
DISPLAY INVISIBLE (-5627 2700);
FORCEADD TAP..1
(-5625 2750);
FORCEPROP 3 LASTPIN (-5675 2750) SIG_NAME M_G_CPU0_SB_DQ<11>
J 0
(-5665 2760);
DISPLAY 0.659574 (-5665 2760);
PAINT MONO (-5665 2760);
DISPLAY INVISIBLE (-5665 2760);
FORCEPROP 1 LASTPIN (-5675 2750) BN 11
J 0
(-5687 2758);
DISPLAY 0.489362 (-5687 2758);
PAINT GREEN (-5687 2758);
FORCEPROP 2 LAST CDS_LIB mstr_standard
J 0
(-5625 2750);
DISPLAY 0.723404 (-5625 2750);
PAINT MONO (-5625 2750);
DISPLAY INVISIBLE (-5625 2750);
FORCEPROP 1 LAST BODY_TYPE PLUMBING
J 0
(-5625 2800);
DISPLAY 0.872340 (-5625 2800);
PAINT GREEN (-5625 2800);
DISPLAY INVISIBLE (-5625 2800);
FORCEPROP 1 LAST HDL_TAP TRUE
J 0
(-5300 2625);
DISPLAY 0.872340 (-5300 2625);
DISPLAY INVISIBLE (-5300 2625);
FORCEPROP 1 LAST PATH I57
J 0
(-5627 2750);
DISPLAY 0.872340 (-5627 2750);
PAINT GREEN (-5627 2750);
DISPLAY INVISIBLE (-5627 2750);
FORCEADD TAP..1
(-5625 2900);
FORCEPROP 3 LASTPIN (-5675 2900) SIG_NAME M_G_CPU0_SB_DQ<14>
J 0
(-5665 2910);
DISPLAY 0.659574 (-5665 2910);
PAINT MONO (-5665 2910);
DISPLAY INVISIBLE (-5665 2910);
FORCEPROP 1 LASTPIN (-5675 2900) BN 14
J 0
(-5687 2908);
DISPLAY 0.489362 (-5687 2908);
PAINT GREEN (-5687 2908);
FORCEPROP 2 LAST CDS_LIB mstr_standard
J 0
(-5625 2900);
DISPLAY 0.723404 (-5625 2900);
PAINT MONO (-5625 2900);
DISPLAY INVISIBLE (-5625 2900);
FORCEPROP 1 LAST BODY_TYPE PLUMBING
J 0
(-5625 2950);
DISPLAY 0.872340 (-5625 2950);
PAINT GREEN (-5625 2950);
DISPLAY INVISIBLE (-5625 2950);
FORCEPROP 1 LAST HDL_TAP TRUE
J 0
(-5300 2775);
DISPLAY 0.872340 (-5300 2775);
DISPLAY INVISIBLE (-5300 2775);
FORCEPROP 1 LAST PATH I58
J 0
(-5627 2900);
DISPLAY 0.872340 (-5627 2900);
PAINT GREEN (-5627 2900);
DISPLAY INVISIBLE (-5627 2900);
FORCEADD TAP..1
(-5625 2850);
FORCEPROP 3 LASTPIN (-5675 2850) SIG_NAME M_G_CPU0_SB_DQ<13>
J 0
(-5665 2860);
DISPLAY 0.659574 (-5665 2860);
PAINT MONO (-5665 2860);
DISPLAY INVISIBLE (-5665 2860);
FORCEPROP 1 LASTPIN (-5675 2850) BN 13
J 0
(-5687 2858);
DISPLAY 0.489362 (-5687 2858);
PAINT GREEN (-5687 2858);
FORCEPROP 2 LAST CDS_LIB mstr_standard
J 0
(-5625 2850);
DISPLAY 0.723404 (-5625 2850);
PAINT MONO (-5625 2850);
DISPLAY INVISIBLE (-5625 2850);
FORCEPROP 1 LAST BODY_TYPE PLUMBING
J 0
(-5625 2900);
DISPLAY 0.872340 (-5625 2900);
PAINT GREEN (-5625 2900);
DISPLAY INVISIBLE (-5625 2900);
FORCEPROP 1 LAST HDL_TAP TRUE
J 0
(-5300 2725);
DISPLAY 0.872340 (-5300 2725);
DISPLAY INVISIBLE (-5300 2725);
FORCEPROP 1 LAST PATH I59
J 0
(-5627 2850);
DISPLAY 0.872340 (-5627 2850);
PAINT GREEN (-5627 2850);
DISPLAY INVISIBLE (-5627 2850);
FORCEADD OFFPAGE..1
(-8125 2900);
FORCEPROP 2 LAST $XR0 92 
J 0
(-8376 2900);
DISPLAY 0.638298 (-8376 2900);
PAINT MONO (-8376 2900);
FORCEPROP 2 LAST CDS_LIB mstr_standard
J 0
(-8125 2900);
DISPLAY 0.808511 (-8125 2900);
DISPLAY INVISIBLE (-8125 2900);
FORCEPROP 1 LAST OFFPAGE TRUE
J 0
(-7800 2775);
DISPLAY 0.872340 (-7800 2775);
PAINT GREEN (-7800 2775);
DISPLAY INVISIBLE (-7800 2775);
FORCEPROP 1 LAST COMMENT_BODY TRUE
J 0
(-8000 2800);
DISPLAY 0.872340 (-8000 2800);
PAINT GREEN (-8000 2800);
DISPLAY INVISIBLE (-8000 2800);
FORCEPROP 2 LAST PATH I6
J 0
(-8375 2950);
DISPLAY 1.021277 (-8375 2950);
DISPLAY INVISIBLE (-8375 2950);
FORCEADD TAP..1
(-5625 2800);
FORCEPROP 3 LASTPIN (-5675 2800) SIG_NAME M_G_CPU0_SB_DQ<12>
J 0
(-5665 2810);
DISPLAY 0.659574 (-5665 2810);
PAINT MONO (-5665 2810);
DISPLAY INVISIBLE (-5665 2810);
FORCEPROP 1 LASTPIN (-5675 2800) BN 12
J 0
(-5687 2808);
DISPLAY 0.489362 (-5687 2808);
PAINT GREEN (-5687 2808);
FORCEPROP 2 LAST CDS_LIB mstr_standard
J 0
(-5625 2800);
DISPLAY 0.723404 (-5625 2800);
PAINT MONO (-5625 2800);
DISPLAY INVISIBLE (-5625 2800);
FORCEPROP 1 LAST BODY_TYPE PLUMBING
J 0
(-5625 2850);
DISPLAY 0.872340 (-5625 2850);
PAINT GREEN (-5625 2850);
DISPLAY INVISIBLE (-5625 2850);
FORCEPROP 1 LAST HDL_TAP TRUE
J 0
(-5300 2675);
DISPLAY 0.872340 (-5300 2675);
DISPLAY INVISIBLE (-5300 2675);
FORCEPROP 1 LAST PATH I60
J 0
(-5627 2800);
DISPLAY 0.872340 (-5627 2800);
PAINT GREEN (-5627 2800);
DISPLAY INVISIBLE (-5627 2800);
FORCEADD TAP..1
(-5625 3000);
FORCEPROP 3 LASTPIN (-5675 3000) SIG_NAME M_G_CPU0_SB_DQ<16>
J 0
(-5665 3010);
DISPLAY 0.659574 (-5665 3010);
PAINT MONO (-5665 3010);
DISPLAY INVISIBLE (-5665 3010);
FORCEPROP 1 LASTPIN (-5675 3000) BN 16
J 0
(-5687 3008);
DISPLAY 0.489362 (-5687 3008);
PAINT GREEN (-5687 3008);
FORCEPROP 2 LAST CDS_LIB mstr_standard
J 0
(-5625 3000);
DISPLAY 0.723404 (-5625 3000);
PAINT MONO (-5625 3000);
DISPLAY INVISIBLE (-5625 3000);
FORCEPROP 1 LAST BODY_TYPE PLUMBING
J 0
(-5625 3050);
DISPLAY 0.872340 (-5625 3050);
PAINT GREEN (-5625 3050);
DISPLAY INVISIBLE (-5625 3050);
FORCEPROP 1 LAST HDL_TAP TRUE
J 0
(-5300 2875);
DISPLAY 0.872340 (-5300 2875);
DISPLAY INVISIBLE (-5300 2875);
FORCEPROP 1 LAST PATH I61
J 0
(-5627 3000);
DISPLAY 0.872340 (-5627 3000);
PAINT GREEN (-5627 3000);
DISPLAY INVISIBLE (-5627 3000);
FORCEADD TAP..1
(-5625 2950);
FORCEPROP 3 LASTPIN (-5675 2950) SIG_NAME M_G_CPU0_SB_DQ<15>
J 0
(-5665 2960);
DISPLAY 0.659574 (-5665 2960);
PAINT MONO (-5665 2960);
DISPLAY INVISIBLE (-5665 2960);
FORCEPROP 1 LASTPIN (-5675 2950) BN 15
J 0
(-5687 2958);
DISPLAY 0.489362 (-5687 2958);
PAINT GREEN (-5687 2958);
FORCEPROP 2 LAST CDS_LIB mstr_standard
J 0
(-5625 2950);
DISPLAY 0.723404 (-5625 2950);
PAINT MONO (-5625 2950);
DISPLAY INVISIBLE (-5625 2950);
FORCEPROP 1 LAST BODY_TYPE PLUMBING
J 0
(-5625 3000);
DISPLAY 0.872340 (-5625 3000);
PAINT GREEN (-5625 3000);
DISPLAY INVISIBLE (-5625 3000);
FORCEPROP 1 LAST HDL_TAP TRUE
J 0
(-5300 2825);
DISPLAY 0.872340 (-5300 2825);
DISPLAY INVISIBLE (-5300 2825);
FORCEPROP 1 LAST PATH I62
J 0
(-5627 2950);
DISPLAY 0.872340 (-5627 2950);
PAINT GREEN (-5627 2950);
DISPLAY INVISIBLE (-5627 2950);
FORCEADD TAP..1
(-5625 3050);
FORCEPROP 3 LASTPIN (-5675 3050) SIG_NAME M_G_CPU0_SB_DQ<17>
J 0
(-5665 3060);
DISPLAY 0.659574 (-5665 3060);
PAINT MONO (-5665 3060);
DISPLAY INVISIBLE (-5665 3060);
FORCEPROP 1 LASTPIN (-5675 3050) BN 17
J 0
(-5687 3058);
DISPLAY 0.489362 (-5687 3058);
PAINT GREEN (-5687 3058);
FORCEPROP 2 LAST CDS_LIB mstr_standard
J 0
(-5625 3050);
DISPLAY 0.723404 (-5625 3050);
PAINT MONO (-5625 3050);
DISPLAY INVISIBLE (-5625 3050);
FORCEPROP 1 LAST BODY_TYPE PLUMBING
J 0
(-5625 3100);
DISPLAY 0.872340 (-5625 3100);
PAINT GREEN (-5625 3100);
DISPLAY INVISIBLE (-5625 3100);
FORCEPROP 1 LAST HDL_TAP TRUE
J 0
(-5300 2925);
DISPLAY 0.872340 (-5300 2925);
DISPLAY INVISIBLE (-5300 2925);
FORCEPROP 1 LAST PATH I63
J 0
(-5627 3050);
DISPLAY 0.872340 (-5627 3050);
PAINT GREEN (-5627 3050);
DISPLAY INVISIBLE (-5627 3050);
FORCEADD TAP..1
(-5625 3150);
FORCEPROP 3 LASTPIN (-5675 3150) SIG_NAME M_G_CPU0_SB_DQ<19>
J 0
(-5665 3160);
DISPLAY 0.659574 (-5665 3160);
PAINT MONO (-5665 3160);
DISPLAY INVISIBLE (-5665 3160);
FORCEPROP 1 LASTPIN (-5675 3150) BN 19
J 0
(-5687 3158);
DISPLAY 0.489362 (-5687 3158);
PAINT GREEN (-5687 3158);
FORCEPROP 2 LAST CDS_LIB mstr_standard
J 0
(-5625 3150);
DISPLAY 0.723404 (-5625 3150);
PAINT MONO (-5625 3150);
DISPLAY INVISIBLE (-5625 3150);
FORCEPROP 1 LAST BODY_TYPE PLUMBING
J 0
(-5625 3200);
DISPLAY 0.872340 (-5625 3200);
PAINT GREEN (-5625 3200);
DISPLAY INVISIBLE (-5625 3200);
FORCEPROP 1 LAST HDL_TAP TRUE
J 0
(-5300 3025);
DISPLAY 0.872340 (-5300 3025);
DISPLAY INVISIBLE (-5300 3025);
FORCEPROP 1 LAST PATH I64
J 0
(-5627 3150);
DISPLAY 0.872340 (-5627 3150);
PAINT GREEN (-5627 3150);
DISPLAY INVISIBLE (-5627 3150);
FORCEADD TAP..1
(-5625 3100);
FORCEPROP 3 LASTPIN (-5675 3100) SIG_NAME M_G_CPU0_SB_DQ<18>
J 0
(-5665 3110);
DISPLAY 0.659574 (-5665 3110);
PAINT MONO (-5665 3110);
DISPLAY INVISIBLE (-5665 3110);
FORCEPROP 1 LASTPIN (-5675 3100) BN 18
J 0
(-5687 3108);
DISPLAY 0.489362 (-5687 3108);
PAINT GREEN (-5687 3108);
FORCEPROP 2 LAST CDS_LIB mstr_standard
J 0
(-5625 3100);
DISPLAY 0.723404 (-5625 3100);
PAINT MONO (-5625 3100);
DISPLAY INVISIBLE (-5625 3100);
FORCEPROP 1 LAST BODY_TYPE PLUMBING
J 0
(-5625 3150);
DISPLAY 0.872340 (-5625 3150);
PAINT GREEN (-5625 3150);
DISPLAY INVISIBLE (-5625 3150);
FORCEPROP 1 LAST HDL_TAP TRUE
J 0
(-5300 2975);
DISPLAY 0.872340 (-5300 2975);
DISPLAY INVISIBLE (-5300 2975);
FORCEPROP 1 LAST PATH I65
J 0
(-5627 3100);
DISPLAY 0.872340 (-5627 3100);
PAINT GREEN (-5627 3100);
DISPLAY INVISIBLE (-5627 3100);
FORCEADD TAP..1
(-5625 3200);
FORCEPROP 3 LASTPIN (-5675 3200) SIG_NAME M_G_CPU0_SB_DQ<20>
J 0
(-5665 3210);
DISPLAY 0.659574 (-5665 3210);
PAINT MONO (-5665 3210);
DISPLAY INVISIBLE (-5665 3210);
FORCEPROP 1 LASTPIN (-5675 3200) BN 20
J 0
(-5687 3208);
DISPLAY 0.489362 (-5687 3208);
PAINT GREEN (-5687 3208);
FORCEPROP 2 LAST CDS_LIB mstr_standard
J 0
(-5625 3200);
DISPLAY 0.723404 (-5625 3200);
PAINT MONO (-5625 3200);
DISPLAY INVISIBLE (-5625 3200);
FORCEPROP 1 LAST BODY_TYPE PLUMBING
J 0
(-5625 3250);
DISPLAY 0.872340 (-5625 3250);
PAINT GREEN (-5625 3250);
DISPLAY INVISIBLE (-5625 3250);
FORCEPROP 1 LAST HDL_TAP TRUE
J 0
(-5300 3075);
DISPLAY 0.872340 (-5300 3075);
DISPLAY INVISIBLE (-5300 3075);
FORCEPROP 1 LAST PATH I66
J 0
(-5627 3200);
DISPLAY 0.872340 (-5627 3200);
PAINT GREEN (-5627 3200);
DISPLAY INVISIBLE (-5627 3200);
FORCEADD TAP..1
(-5625 3250);
FORCEPROP 3 LASTPIN (-5675 3250) SIG_NAME M_G_CPU0_SB_DQ<21>
J 0
(-5665 3260);
DISPLAY 0.659574 (-5665 3260);
PAINT MONO (-5665 3260);
DISPLAY INVISIBLE (-5665 3260);
FORCEPROP 1 LASTPIN (-5675 3250) BN 21
J 0
(-5687 3258);
DISPLAY 0.489362 (-5687 3258);
PAINT GREEN (-5687 3258);
FORCEPROP 2 LAST CDS_LIB mstr_standard
J 0
(-5625 3250);
DISPLAY 0.723404 (-5625 3250);
PAINT MONO (-5625 3250);
DISPLAY INVISIBLE (-5625 3250);
FORCEPROP 1 LAST BODY_TYPE PLUMBING
J 0
(-5625 3300);
DISPLAY 0.872340 (-5625 3300);
PAINT GREEN (-5625 3300);
DISPLAY INVISIBLE (-5625 3300);
FORCEPROP 1 LAST HDL_TAP TRUE
J 0
(-5300 3125);
DISPLAY 0.872340 (-5300 3125);
DISPLAY INVISIBLE (-5300 3125);
FORCEPROP 1 LAST PATH I67
J 0
(-5627 3250);
DISPLAY 0.872340 (-5627 3250);
PAINT GREEN (-5627 3250);
DISPLAY INVISIBLE (-5627 3250);
FORCEADD TAP..1
(-5625 3300);
FORCEPROP 3 LASTPIN (-5675 3300) SIG_NAME M_G_CPU0_SB_DQ<22>
J 0
(-5665 3310);
DISPLAY 0.659574 (-5665 3310);
PAINT MONO (-5665 3310);
DISPLAY INVISIBLE (-5665 3310);
FORCEPROP 1 LASTPIN (-5675 3300) BN 22
J 0
(-5687 3308);
DISPLAY 0.489362 (-5687 3308);
PAINT GREEN (-5687 3308);
FORCEPROP 2 LAST CDS_LIB mstr_standard
J 0
(-5625 3300);
DISPLAY 0.723404 (-5625 3300);
PAINT MONO (-5625 3300);
DISPLAY INVISIBLE (-5625 3300);
FORCEPROP 1 LAST BODY_TYPE PLUMBING
J 0
(-5625 3350);
DISPLAY 0.872340 (-5625 3350);
PAINT GREEN (-5625 3350);
DISPLAY INVISIBLE (-5625 3350);
FORCEPROP 1 LAST HDL_TAP TRUE
J 0
(-5300 3175);
DISPLAY 0.872340 (-5300 3175);
DISPLAY INVISIBLE (-5300 3175);
FORCEPROP 1 LAST PATH I68
J 0
(-5627 3300);
DISPLAY 0.872340 (-5627 3300);
PAINT GREEN (-5627 3300);
DISPLAY INVISIBLE (-5627 3300);
FORCEADD TAP..1
(-5625 3400);
FORCEPROP 3 LASTPIN (-5675 3400) SIG_NAME M_G_CPU0_SB_DQ<24>
J 0
(-5665 3410);
DISPLAY 0.659574 (-5665 3410);
PAINT MONO (-5665 3410);
DISPLAY INVISIBLE (-5665 3410);
FORCEPROP 1 LASTPIN (-5675 3400) BN 24
J 0
(-5687 3408);
DISPLAY 0.489362 (-5687 3408);
PAINT GREEN (-5687 3408);
FORCEPROP 2 LAST CDS_LIB mstr_standard
J 0
(-5625 3400);
DISPLAY 0.723404 (-5625 3400);
PAINT MONO (-5625 3400);
DISPLAY INVISIBLE (-5625 3400);
FORCEPROP 1 LAST BODY_TYPE PLUMBING
J 0
(-5625 3450);
DISPLAY 0.872340 (-5625 3450);
PAINT GREEN (-5625 3450);
DISPLAY INVISIBLE (-5625 3450);
FORCEPROP 1 LAST HDL_TAP TRUE
J 0
(-5300 3275);
DISPLAY 0.872340 (-5300 3275);
DISPLAY INVISIBLE (-5300 3275);
FORCEPROP 1 LAST PATH I69
J 0
(-5627 3400);
DISPLAY 0.872340 (-5627 3400);
PAINT GREEN (-5627 3400);
DISPLAY INVISIBLE (-5627 3400);
FORCEADD OFFPAGE..5
(-7925 3050);
FORCEPROP 2 LAST $XR0 16 
J 0
(-8149 3050);
DISPLAY 0.638298 (-8149 3050);
PAINT MONO (-8149 3050);
FORCEPROP 2 LAST CDS_LIB mstr_standard
J 0
(-7925 3050);
DISPLAY INVISIBLE (-7925 3050);
FORCEPROP 1 LAST OFFPAGE TRUE
J 0
(-7600 2925);
DISPLAY 0.872340 (-7600 2925);
PAINT GREEN (-7600 2925);
DISPLAY INVISIBLE (-7600 2925);
FORCEPROP 1 LAST COMMENT_BODY TRUE
J 0
(-7825 2975);
DISPLAY 0.872340 (-7825 2975);
PAINT GREEN (-7825 2975);
DISPLAY INVISIBLE (-7825 2975);
FORCEPROP 2 LAST PATH I7
J 0
(-8175 3100);
DISPLAY 1.021277 (-8175 3100);
DISPLAY INVISIBLE (-8175 3100);
FORCEADD TAP..1
(-5625 3350);
FORCEPROP 3 LASTPIN (-5675 3350) SIG_NAME M_G_CPU0_SB_DQ<23>
J 0
(-5665 3360);
DISPLAY 0.659574 (-5665 3360);
PAINT MONO (-5665 3360);
DISPLAY INVISIBLE (-5665 3360);
FORCEPROP 1 LASTPIN (-5675 3350) BN 23
J 0
(-5687 3358);
DISPLAY 0.489362 (-5687 3358);
PAINT GREEN (-5687 3358);
FORCEPROP 2 LAST CDS_LIB mstr_standard
J 0
(-5625 3350);
DISPLAY 0.723404 (-5625 3350);
PAINT MONO (-5625 3350);
DISPLAY INVISIBLE (-5625 3350);
FORCEPROP 1 LAST BODY_TYPE PLUMBING
J 0
(-5625 3400);
DISPLAY 0.872340 (-5625 3400);
PAINT GREEN (-5625 3400);
DISPLAY INVISIBLE (-5625 3400);
FORCEPROP 1 LAST HDL_TAP TRUE
J 0
(-5300 3225);
DISPLAY 0.872340 (-5300 3225);
DISPLAY INVISIBLE (-5300 3225);
FORCEPROP 1 LAST PATH I70
J 0
(-5627 3350);
DISPLAY 0.872340 (-5627 3350);
PAINT GREEN (-5627 3350);
DISPLAY INVISIBLE (-5627 3350);
FORCEADD TAP..1
(-5625 3450);
FORCEPROP 3 LASTPIN (-5675 3450) SIG_NAME M_G_CPU0_SB_DQ<25>
J 0
(-5665 3460);
DISPLAY 0.659574 (-5665 3460);
PAINT MONO (-5665 3460);
DISPLAY INVISIBLE (-5665 3460);
FORCEPROP 1 LASTPIN (-5675 3450) BN 25
J 0
(-5687 3458);
DISPLAY 0.489362 (-5687 3458);
PAINT GREEN (-5687 3458);
FORCEPROP 2 LAST CDS_LIB mstr_standard
J 0
(-5625 3450);
DISPLAY 0.723404 (-5625 3450);
PAINT MONO (-5625 3450);
DISPLAY INVISIBLE (-5625 3450);
FORCEPROP 1 LAST BODY_TYPE PLUMBING
J 0
(-5625 3500);
DISPLAY 0.872340 (-5625 3500);
PAINT GREEN (-5625 3500);
DISPLAY INVISIBLE (-5625 3500);
FORCEPROP 1 LAST HDL_TAP TRUE
J 0
(-5300 3325);
DISPLAY 0.872340 (-5300 3325);
DISPLAY INVISIBLE (-5300 3325);
FORCEPROP 1 LAST PATH I71
J 0
(-5627 3450);
DISPLAY 0.872340 (-5627 3450);
PAINT GREEN (-5627 3450);
DISPLAY INVISIBLE (-5627 3450);
FORCEADD TAP..1
(-5625 3500);
FORCEPROP 3 LASTPIN (-5675 3500) SIG_NAME M_G_CPU0_SB_DQ<26>
J 0
(-5665 3510);
DISPLAY 0.659574 (-5665 3510);
PAINT MONO (-5665 3510);
DISPLAY INVISIBLE (-5665 3510);
FORCEPROP 1 LASTPIN (-5675 3500) BN 26
J 0
(-5687 3508);
DISPLAY 0.489362 (-5687 3508);
PAINT GREEN (-5687 3508);
FORCEPROP 2 LAST CDS_LIB mstr_standard
J 0
(-5625 3500);
DISPLAY 0.723404 (-5625 3500);
PAINT MONO (-5625 3500);
DISPLAY INVISIBLE (-5625 3500);
FORCEPROP 1 LAST BODY_TYPE PLUMBING
J 0
(-5625 3550);
DISPLAY 0.872340 (-5625 3550);
PAINT GREEN (-5625 3550);
DISPLAY INVISIBLE (-5625 3550);
FORCEPROP 1 LAST HDL_TAP TRUE
J 0
(-5300 3375);
DISPLAY 0.872340 (-5300 3375);
DISPLAY INVISIBLE (-5300 3375);
FORCEPROP 1 LAST PATH I72
J 0
(-5627 3500);
DISPLAY 0.872340 (-5627 3500);
PAINT GREEN (-5627 3500);
DISPLAY INVISIBLE (-5627 3500);
FORCEADD TAP..1
(-5625 3550);
FORCEPROP 3 LASTPIN (-5675 3550) SIG_NAME M_G_CPU0_SB_DQ<27>
J 0
(-5665 3560);
DISPLAY 0.659574 (-5665 3560);
PAINT MONO (-5665 3560);
DISPLAY INVISIBLE (-5665 3560);
FORCEPROP 1 LASTPIN (-5675 3550) BN 27
J 0
(-5687 3558);
DISPLAY 0.489362 (-5687 3558);
PAINT GREEN (-5687 3558);
FORCEPROP 2 LAST CDS_LIB mstr_standard
J 0
(-5625 3550);
DISPLAY 0.723404 (-5625 3550);
PAINT MONO (-5625 3550);
DISPLAY INVISIBLE (-5625 3550);
FORCEPROP 1 LAST BODY_TYPE PLUMBING
J 0
(-5625 3600);
DISPLAY 0.872340 (-5625 3600);
PAINT GREEN (-5625 3600);
DISPLAY INVISIBLE (-5625 3600);
FORCEPROP 1 LAST HDL_TAP TRUE
J 0
(-5300 3425);
DISPLAY 0.872340 (-5300 3425);
DISPLAY INVISIBLE (-5300 3425);
FORCEPROP 1 LAST PATH I73
J 0
(-5627 3550);
DISPLAY 0.872340 (-5627 3550);
PAINT GREEN (-5627 3550);
DISPLAY INVISIBLE (-5627 3550);
FORCEADD TAP..1
(-5625 3650);
FORCEPROP 3 LASTPIN (-5675 3650) SIG_NAME M_G_CPU0_SB_DQ<29>
J 0
(-5665 3660);
DISPLAY 0.659574 (-5665 3660);
PAINT MONO (-5665 3660);
DISPLAY INVISIBLE (-5665 3660);
FORCEPROP 1 LASTPIN (-5675 3650) BN 29
J 0
(-5687 3658);
DISPLAY 0.489362 (-5687 3658);
PAINT GREEN (-5687 3658);
FORCEPROP 2 LAST CDS_LIB mstr_standard
J 0
(-5625 3650);
DISPLAY 0.723404 (-5625 3650);
PAINT MONO (-5625 3650);
DISPLAY INVISIBLE (-5625 3650);
FORCEPROP 1 LAST BODY_TYPE PLUMBING
J 0
(-5625 3700);
DISPLAY 0.872340 (-5625 3700);
PAINT GREEN (-5625 3700);
DISPLAY INVISIBLE (-5625 3700);
FORCEPROP 1 LAST HDL_TAP TRUE
J 0
(-5300 3525);
DISPLAY 0.872340 (-5300 3525);
DISPLAY INVISIBLE (-5300 3525);
FORCEPROP 1 LAST PATH I74
J 0
(-5627 3650);
DISPLAY 0.872340 (-5627 3650);
PAINT GREEN (-5627 3650);
DISPLAY INVISIBLE (-5627 3650);
FORCEADD TAP..1
(-5625 3600);
FORCEPROP 3 LASTPIN (-5675 3600) SIG_NAME M_G_CPU0_SB_DQ<28>
J 0
(-5665 3610);
DISPLAY 0.659574 (-5665 3610);
PAINT MONO (-5665 3610);
DISPLAY INVISIBLE (-5665 3610);
FORCEPROP 1 LASTPIN (-5675 3600) BN 28
J 0
(-5687 3608);
DISPLAY 0.489362 (-5687 3608);
PAINT GREEN (-5687 3608);
FORCEPROP 2 LAST CDS_LIB mstr_standard
J 0
(-5625 3600);
DISPLAY 0.723404 (-5625 3600);
PAINT MONO (-5625 3600);
DISPLAY INVISIBLE (-5625 3600);
FORCEPROP 1 LAST BODY_TYPE PLUMBING
J 0
(-5625 3650);
DISPLAY 0.872340 (-5625 3650);
PAINT GREEN (-5625 3650);
DISPLAY INVISIBLE (-5625 3650);
FORCEPROP 1 LAST HDL_TAP TRUE
J 0
(-5300 3475);
DISPLAY 0.872340 (-5300 3475);
DISPLAY INVISIBLE (-5300 3475);
FORCEPROP 1 LAST PATH I75
J 0
(-5627 3600);
DISPLAY 0.872340 (-5627 3600);
PAINT GREEN (-5627 3600);
DISPLAY INVISIBLE (-5627 3600);
FORCEADD TAP..1
(-5625 3700);
FORCEPROP 3 LASTPIN (-5675 3700) SIG_NAME M_G_CPU0_SB_DQ<30>
J 0
(-5665 3710);
DISPLAY 0.659574 (-5665 3710);
PAINT MONO (-5665 3710);
DISPLAY INVISIBLE (-5665 3710);
FORCEPROP 1 LASTPIN (-5675 3700) BN 30
J 0
(-5687 3708);
DISPLAY 0.489362 (-5687 3708);
PAINT GREEN (-5687 3708);
FORCEPROP 2 LAST CDS_LIB mstr_standard
J 0
(-5625 3700);
DISPLAY 0.723404 (-5625 3700);
PAINT MONO (-5625 3700);
DISPLAY INVISIBLE (-5625 3700);
FORCEPROP 1 LAST BODY_TYPE PLUMBING
J 0
(-5625 3750);
DISPLAY 0.872340 (-5625 3750);
PAINT GREEN (-5625 3750);
DISPLAY INVISIBLE (-5625 3750);
FORCEPROP 1 LAST HDL_TAP TRUE
J 0
(-5300 3575);
DISPLAY 0.872340 (-5300 3575);
DISPLAY INVISIBLE (-5300 3575);
FORCEPROP 1 LAST PATH I76
J 0
(-5627 3700);
DISPLAY 0.872340 (-5627 3700);
PAINT GREEN (-5627 3700);
DISPLAY INVISIBLE (-5627 3700);
FORCEADD TAP..1
(-5625 3750);
FORCEPROP 3 LASTPIN (-5675 3750) SIG_NAME M_G_CPU0_SB_DQ<31>
J 0
(-5665 3760);
DISPLAY 0.659574 (-5665 3760);
PAINT MONO (-5665 3760);
DISPLAY INVISIBLE (-5665 3760);
FORCEPROP 1 LASTPIN (-5675 3750) BN 31
J 0
(-5687 3758);
DISPLAY 0.489362 (-5687 3758);
PAINT GREEN (-5687 3758);
FORCEPROP 2 LAST CDS_LIB mstr_standard
J 0
(-5625 3750);
DISPLAY 0.723404 (-5625 3750);
PAINT MONO (-5625 3750);
DISPLAY INVISIBLE (-5625 3750);
FORCEPROP 1 LAST BODY_TYPE PLUMBING
J 0
(-5625 3800);
DISPLAY 0.872340 (-5625 3800);
PAINT GREEN (-5625 3800);
DISPLAY INVISIBLE (-5625 3800);
FORCEPROP 1 LAST HDL_TAP TRUE
J 0
(-5300 3625);
DISPLAY 0.872340 (-5300 3625);
DISPLAY INVISIBLE (-5300 3625);
FORCEPROP 1 LAST PATH I77
J 0
(-5627 3750);
DISPLAY 0.872340 (-5627 3750);
PAINT GREEN (-5627 3750);
DISPLAY INVISIBLE (-5627 3750);
FORCEADD TAP..1
(-5625 3900);
FORCEPROP 3 LASTPIN (-5675 3900) SIG_NAME M_G_CPU0_SA_DQ<1>
J 0
(-5665 3910);
DISPLAY 0.659574 (-5665 3910);
PAINT MONO (-5665 3910);
DISPLAY INVISIBLE (-5665 3910);
FORCEPROP 1 LASTPIN (-5675 3900) BN 1
J 0
(-5687 3908);
DISPLAY 0.489362 (-5687 3908);
PAINT GREEN (-5687 3908);
FORCEPROP 2 LAST CDS_LIB mstr_standard
J 0
(-5625 3900);
DISPLAY 0.723404 (-5625 3900);
PAINT MONO (-5625 3900);
DISPLAY INVISIBLE (-5625 3900);
FORCEPROP 1 LAST BODY_TYPE PLUMBING
J 0
(-5625 3950);
DISPLAY 0.872340 (-5625 3950);
PAINT GREEN (-5625 3950);
DISPLAY INVISIBLE (-5625 3950);
FORCEPROP 1 LAST HDL_TAP TRUE
J 0
(-5300 3775);
DISPLAY 0.872340 (-5300 3775);
DISPLAY INVISIBLE (-5300 3775);
FORCEPROP 1 LAST PATH I78
J 0
(-5627 3900);
DISPLAY 0.872340 (-5627 3900);
PAINT GREEN (-5627 3900);
DISPLAY INVISIBLE (-5627 3900);
FORCEADD TAP..1
(-5625 3850);
FORCEPROP 3 LASTPIN (-5675 3850) SIG_NAME M_G_CPU0_SA_DQ<0>
J 0
(-5665 3860);
DISPLAY 0.659574 (-5665 3860);
PAINT MONO (-5665 3860);
DISPLAY INVISIBLE (-5665 3860);
FORCEPROP 1 LASTPIN (-5675 3850) BN 0
J 0
(-5687 3858);
DISPLAY 0.489362 (-5687 3858);
PAINT GREEN (-5687 3858);
FORCEPROP 2 LAST CDS_LIB mstr_standard
J 0
(-5625 3850);
DISPLAY 0.723404 (-5625 3850);
PAINT MONO (-5625 3850);
DISPLAY INVISIBLE (-5625 3850);
FORCEPROP 1 LAST BODY_TYPE PLUMBING
J 0
(-5625 3900);
DISPLAY 0.872340 (-5625 3900);
PAINT GREEN (-5625 3900);
DISPLAY INVISIBLE (-5625 3900);
FORCEPROP 1 LAST HDL_TAP TRUE
J 0
(-5300 3725);
DISPLAY 0.872340 (-5300 3725);
DISPLAY INVISIBLE (-5300 3725);
FORCEPROP 1 LAST PATH I79
J 0
(-5627 3850);
DISPLAY 0.872340 (-5627 3850);
PAINT GREEN (-5627 3850);
DISPLAY INVISIBLE (-5627 3850);
FORCEADD VCC_CORE..1
(-8400 3450);
FORCEPROP 3 LASTPIN (-8400 3400) SIG_NAME P3V3_AUX\g
J 0
(-8390 3410);
DISPLAY 0.659574 (-8390 3410);
PAINT MONO (-8390 3410);
DISPLAY INVISIBLE (-8390 3410);
FORCEPROP 1 LAST HDL_POWER P3V3_AUX
J 1
(-8400 3500);
DISPLAY 0.489362 (-8400 3500);
PAINT GREEN (-8400 3500);
FORCEPROP 2 LAST CDS_LIB mstr_symbols
J 0
(-8400 3450);
PAINT MONO (-8400 3450);
DISPLAY INVISIBLE (-8400 3450);
FORCEPROP 0 LAST VOLTAGE 3.3
J 0
(-8675 3600);
DISPLAY 1.021277 (-8675 3600);
PAINT SKYBLUE (-8675 3600);
DISPLAY INVISIBLE (-8675 3600);
FORCEPROP 2 LAST ROOM PVCCINFAON_CPU0_CTRL
J 0
(-8400 3550);
DISPLAY 0.808511 (-8400 3550);
PAINT RED (-8400 3550);
DISPLAY INVISIBLE (-8400 3550);
FORCEPROP 1 LAST PATH I8
J 0
(-8350 3475);
DISPLAY 0.872340 (-8350 3475);
PAINT AQUA (-8350 3475);
DISPLAY INVISIBLE (-8350 3475);
FORCEADD TAP..1
(-5625 4000);
FORCEPROP 3 LASTPIN (-5675 4000) SIG_NAME M_G_CPU0_SA_DQ<3>
J 0
(-5665 4010);
DISPLAY 0.659574 (-5665 4010);
PAINT MONO (-5665 4010);
DISPLAY INVISIBLE (-5665 4010);
FORCEPROP 1 LASTPIN (-5675 4000) BN 3
J 0
(-5687 4008);
DISPLAY 0.489362 (-5687 4008);
PAINT GREEN (-5687 4008);
FORCEPROP 2 LAST CDS_LIB mstr_standard
J 0
(-5625 4000);
DISPLAY 0.723404 (-5625 4000);
PAINT MONO (-5625 4000);
DISPLAY INVISIBLE (-5625 4000);
FORCEPROP 1 LAST BODY_TYPE PLUMBING
J 0
(-5625 4050);
DISPLAY 0.872340 (-5625 4050);
PAINT GREEN (-5625 4050);
DISPLAY INVISIBLE (-5625 4050);
FORCEPROP 1 LAST HDL_TAP TRUE
J 0
(-5300 3875);
DISPLAY 0.872340 (-5300 3875);
DISPLAY INVISIBLE (-5300 3875);
FORCEPROP 1 LAST PATH I80
J 0
(-5627 4000);
DISPLAY 0.872340 (-5627 4000);
PAINT GREEN (-5627 4000);
DISPLAY INVISIBLE (-5627 4000);
FORCEADD TAP..1
(-5625 4050);
FORCEPROP 3 LASTPIN (-5675 4050) SIG_NAME M_G_CPU0_SA_DQ<4>
J 0
(-5665 4060);
DISPLAY 0.659574 (-5665 4060);
PAINT MONO (-5665 4060);
DISPLAY INVISIBLE (-5665 4060);
FORCEPROP 1 LASTPIN (-5675 4050) BN 4
J 0
(-5687 4058);
DISPLAY 0.489362 (-5687 4058);
PAINT GREEN (-5687 4058);
FORCEPROP 2 LAST CDS_LIB mstr_standard
J 0
(-5625 4050);
DISPLAY 0.723404 (-5625 4050);
PAINT MONO (-5625 4050);
DISPLAY INVISIBLE (-5625 4050);
FORCEPROP 1 LAST BODY_TYPE PLUMBING
J 0
(-5625 4100);
DISPLAY 0.872340 (-5625 4100);
PAINT GREEN (-5625 4100);
DISPLAY INVISIBLE (-5625 4100);
FORCEPROP 1 LAST HDL_TAP TRUE
J 0
(-5300 3925);
DISPLAY 0.872340 (-5300 3925);
DISPLAY INVISIBLE (-5300 3925);
FORCEPROP 1 LAST PATH I81
J 0
(-5627 4050);
DISPLAY 0.872340 (-5627 4050);
PAINT GREEN (-5627 4050);
DISPLAY INVISIBLE (-5627 4050);
FORCEADD TAP..1
(-5625 3950);
FORCEPROP 3 LASTPIN (-5675 3950) SIG_NAME M_G_CPU0_SA_DQ<2>
J 0
(-5665 3960);
DISPLAY 0.659574 (-5665 3960);
PAINT MONO (-5665 3960);
DISPLAY INVISIBLE (-5665 3960);
FORCEPROP 1 LASTPIN (-5675 3950) BN 2
J 0
(-5687 3958);
DISPLAY 0.489362 (-5687 3958);
PAINT GREEN (-5687 3958);
FORCEPROP 2 LAST CDS_LIB mstr_standard
J 0
(-5625 3950);
DISPLAY 0.723404 (-5625 3950);
PAINT MONO (-5625 3950);
DISPLAY INVISIBLE (-5625 3950);
FORCEPROP 1 LAST BODY_TYPE PLUMBING
J 0
(-5625 4000);
DISPLAY 0.872340 (-5625 4000);
PAINT GREEN (-5625 4000);
DISPLAY INVISIBLE (-5625 4000);
FORCEPROP 1 LAST HDL_TAP TRUE
J 0
(-5300 3825);
DISPLAY 0.872340 (-5300 3825);
DISPLAY INVISIBLE (-5300 3825);
FORCEPROP 1 LAST PATH I82
J 0
(-5627 3950);
DISPLAY 0.872340 (-5627 3950);
PAINT GREEN (-5627 3950);
DISPLAY INVISIBLE (-5627 3950);
FORCEADD OFFPAGE..3
(-5025 3800);
FORCEPROP 2 LAST $XR0 16 
J 0
(-4811 3800);
DISPLAY 0.638298 (-4811 3800);
PAINT MONO (-4811 3800);
FORCEPROP 2 LAST CDS_LIB mstr_standard
J 0
(-5025 3800);
DISPLAY 0.723404 (-5025 3800);
PAINT MONO (-5025 3800);
DISPLAY INVISIBLE (-5025 3800);
FORCEPROP 1 LAST OFFPAGE TRUE
J 0
(-4700 3675);
DISPLAY 0.872340 (-4700 3675);
PAINT GREEN (-4700 3675);
DISPLAY INVISIBLE (-4700 3675);
FORCEPROP 1 LAST COMMENT_BODY TRUE
J 0
(-5075 3700);
DISPLAY 0.872340 (-5075 3700);
PAINT GREEN (-5075 3700);
DISPLAY INVISIBLE (-5075 3700);
FORCEPROP 2 LAST PATH I83
J 0
(-4700 3850);
DISPLAY 1.021277 (-4700 3850);
DISPLAY INVISIBLE (-4700 3850);
FORCEADD TAP..1
R 2
(-7325 4700);
FORCEPROP 3 LASTPIN (-7275 4700) SIG_NAME M_G_CPU0_SB_CA<0>
J 0
(-7265 4710);
DISPLAY 0.659574 (-7265 4710);
PAINT MONO (-7265 4710);
DISPLAY INVISIBLE (-7265 4710);
FORCEPROP 1 LASTPIN (-7275 4700) BN 0
J 2
(-7263 4708);
DISPLAY 0.489362 (-7263 4708);
PAINT GREEN (-7263 4708);
FORCEPROP 2 LAST CDS_LIB mstr_standard
J 0
(-7325 4700);
DISPLAY 0.723404 (-7325 4700);
PAINT MONO (-7325 4700);
DISPLAY INVISIBLE (-7325 4700);
FORCEPROP 1 LAST BODY_TYPE PLUMBING
J 2
(-7325 4750);
DISPLAY 0.872340 (-7325 4750);
PAINT GREEN (-7325 4750);
DISPLAY INVISIBLE (-7325 4750);
FORCEPROP 1 LAST HDL_TAP TRUE
J 2
(-7650 4575);
DISPLAY 0.872340 (-7650 4575);
DISPLAY INVISIBLE (-7650 4575);
FORCEPROP 1 LAST PATH I85
J 2
(-7323 4700);
DISPLAY 0.872340 (-7323 4700);
PAINT GREEN (-7323 4700);
DISPLAY INVISIBLE (-7323 4700);
FORCEADD TAP..1
R 2
(-7325 4750);
FORCEPROP 3 LASTPIN (-7275 4750) SIG_NAME M_G_CPU0_SB_CA<1>
J 0
(-7265 4760);
DISPLAY 0.659574 (-7265 4760);
PAINT MONO (-7265 4760);
DISPLAY INVISIBLE (-7265 4760);
FORCEPROP 1 LASTPIN (-7275 4750) BN 1
J 2
(-7263 4758);
DISPLAY 0.489362 (-7263 4758);
PAINT GREEN (-7263 4758);
FORCEPROP 2 LAST CDS_LIB mstr_standard
J 0
(-7325 4750);
DISPLAY 0.723404 (-7325 4750);
PAINT MONO (-7325 4750);
DISPLAY INVISIBLE (-7325 4750);
FORCEPROP 1 LAST BODY_TYPE PLUMBING
J 2
(-7325 4800);
DISPLAY 0.872340 (-7325 4800);
PAINT GREEN (-7325 4800);
DISPLAY INVISIBLE (-7325 4800);
FORCEPROP 1 LAST HDL_TAP TRUE
J 2
(-7650 4625);
DISPLAY 0.872340 (-7650 4625);
DISPLAY INVISIBLE (-7650 4625);
FORCEPROP 1 LAST PATH I86
J 2
(-7323 4750);
DISPLAY 0.872340 (-7323 4750);
PAINT GREEN (-7323 4750);
DISPLAY INVISIBLE (-7323 4750);
FORCEADD TAP..1
R 2
(-7325 4800);
FORCEPROP 3 LASTPIN (-7275 4800) SIG_NAME M_G_CPU0_SB_CA<2>
J 0
(-7265 4810);
DISPLAY 0.659574 (-7265 4810);
PAINT MONO (-7265 4810);
DISPLAY INVISIBLE (-7265 4810);
FORCEPROP 1 LASTPIN (-7275 4800) BN 2
J 2
(-7263 4808);
DISPLAY 0.489362 (-7263 4808);
PAINT GREEN (-7263 4808);
FORCEPROP 2 LAST CDS_LIB mstr_standard
J 0
(-7325 4800);
DISPLAY 0.723404 (-7325 4800);
PAINT MONO (-7325 4800);
DISPLAY INVISIBLE (-7325 4800);
FORCEPROP 1 LAST BODY_TYPE PLUMBING
J 2
(-7325 4850);
DISPLAY 0.872340 (-7325 4850);
PAINT GREEN (-7325 4850);
DISPLAY INVISIBLE (-7325 4850);
FORCEPROP 1 LAST HDL_TAP TRUE
J 2
(-7650 4675);
DISPLAY 0.872340 (-7650 4675);
DISPLAY INVISIBLE (-7650 4675);
FORCEPROP 1 LAST PATH I87
J 2
(-7323 4800);
DISPLAY 0.872340 (-7323 4800);
PAINT GREEN (-7323 4800);
DISPLAY INVISIBLE (-7323 4800);
FORCEADD TAP..1
R 2
(-7325 4850);
FORCEPROP 3 LASTPIN (-7275 4850) SIG_NAME M_G_CPU0_SB_CA<3>
J 0
(-7265 4860);
DISPLAY 0.659574 (-7265 4860);
PAINT MONO (-7265 4860);
DISPLAY INVISIBLE (-7265 4860);
FORCEPROP 1 LASTPIN (-7275 4850) BN 3
J 2
(-7263 4858);
DISPLAY 0.489362 (-7263 4858);
PAINT GREEN (-7263 4858);
FORCEPROP 2 LAST CDS_LIB mstr_standard
J 0
(-7325 4850);
DISPLAY 0.723404 (-7325 4850);
PAINT MONO (-7325 4850);
DISPLAY INVISIBLE (-7325 4850);
FORCEPROP 1 LAST BODY_TYPE PLUMBING
J 2
(-7325 4900);
DISPLAY 0.872340 (-7325 4900);
PAINT GREEN (-7325 4900);
DISPLAY INVISIBLE (-7325 4900);
FORCEPROP 1 LAST HDL_TAP TRUE
J 2
(-7650 4725);
DISPLAY 0.872340 (-7650 4725);
DISPLAY INVISIBLE (-7650 4725);
FORCEPROP 1 LAST PATH I88
J 2
(-7323 4850);
DISPLAY 0.872340 (-7323 4850);
PAINT GREEN (-7323 4850);
DISPLAY INVISIBLE (-7323 4850);
FORCEADD TAP..1
R 2
(-7325 4900);
FORCEPROP 3 LASTPIN (-7275 4900) SIG_NAME M_G_CPU0_SB_CA<4>
J 0
(-7265 4910);
DISPLAY 0.659574 (-7265 4910);
PAINT MONO (-7265 4910);
DISPLAY INVISIBLE (-7265 4910);
FORCEPROP 1 LASTPIN (-7275 4900) BN 4
J 2
(-7263 4908);
DISPLAY 0.489362 (-7263 4908);
PAINT GREEN (-7263 4908);
FORCEPROP 2 LAST CDS_LIB mstr_standard
J 0
(-7325 4900);
DISPLAY 0.723404 (-7325 4900);
PAINT MONO (-7325 4900);
DISPLAY INVISIBLE (-7325 4900);
FORCEPROP 1 LAST BODY_TYPE PLUMBING
J 2
(-7325 4950);
DISPLAY 0.872340 (-7325 4950);
PAINT GREEN (-7325 4950);
DISPLAY INVISIBLE (-7325 4950);
FORCEPROP 1 LAST HDL_TAP TRUE
J 2
(-7650 4775);
DISPLAY 0.872340 (-7650 4775);
DISPLAY INVISIBLE (-7650 4775);
FORCEPROP 1 LAST PATH I89
J 2
(-7323 4900);
DISPLAY 0.872340 (-7323 4900);
PAINT GREEN (-7323 4900);
DISPLAY INVISIBLE (-7323 4900);
FORCEADD OFFPAGE..1
(-7925 3100);
FORCEPROP 2 LAST $XR0 16 
J 0
(-8176 3100);
DISPLAY 0.638298 (-8176 3100);
PAINT MONO (-8176 3100);
FORCEPROP 2 LAST CDS_LIB mstr_standard
J 0
(-7925 3100);
DISPLAY 0.808511 (-7925 3100);
DISPLAY INVISIBLE (-7925 3100);
FORCEPROP 1 LAST OFFPAGE TRUE
J 0
(-7600 2975);
DISPLAY 0.872340 (-7600 2975);
PAINT GREEN (-7600 2975);
DISPLAY INVISIBLE (-7600 2975);
FORCEPROP 1 LAST COMMENT_BODY TRUE
J 0
(-7800 3000);
DISPLAY 0.872340 (-7800 3000);
PAINT GREEN (-7800 3000);
DISPLAY INVISIBLE (-7800 3000);
FORCEPROP 2 LAST PATH I9
J 0
(-8175 3150);
DISPLAY 1.021277 (-8175 3150);
DISPLAY INVISIBLE (-8175 3150);
FORCEADD TAP..1
R 2
(-7325 4950);
FORCEPROP 3 LASTPIN (-7275 4950) SIG_NAME M_G_CPU0_SB_CA<5>
J 0
(-7265 4960);
DISPLAY 0.659574 (-7265 4960);
PAINT MONO (-7265 4960);
DISPLAY INVISIBLE (-7265 4960);
FORCEPROP 1 LASTPIN (-7275 4950) BN 5
J 2
(-7263 4958);
DISPLAY 0.489362 (-7263 4958);
PAINT GREEN (-7263 4958);
FORCEPROP 2 LAST CDS_LIB mstr_standard
J 0
(-7325 4950);
DISPLAY 0.723404 (-7325 4950);
PAINT MONO (-7325 4950);
DISPLAY INVISIBLE (-7325 4950);
FORCEPROP 1 LAST BODY_TYPE PLUMBING
J 2
(-7325 5000);
DISPLAY 0.872340 (-7325 5000);
PAINT GREEN (-7325 5000);
DISPLAY INVISIBLE (-7325 5000);
FORCEPROP 1 LAST HDL_TAP TRUE
J 2
(-7650 4825);
DISPLAY 0.872340 (-7650 4825);
DISPLAY INVISIBLE (-7650 4825);
FORCEPROP 1 LAST PATH I90
J 2
(-7323 4950);
DISPLAY 0.872340 (-7323 4950);
PAINT GREEN (-7323 4950);
DISPLAY INVISIBLE (-7323 4950);
FORCEADD TAP..1
R 2
(-7325 5000);
FORCEPROP 3 LASTPIN (-7275 5000) SIG_NAME M_G_CPU0_SB_CA<6>
J 0
(-7265 5010);
DISPLAY 0.659574 (-7265 5010);
PAINT MONO (-7265 5010);
DISPLAY INVISIBLE (-7265 5010);
FORCEPROP 1 LASTPIN (-7275 5000) BN 6
J 2
(-7263 5008);
DISPLAY 0.489362 (-7263 5008);
PAINT GREEN (-7263 5008);
FORCEPROP 2 LAST CDS_LIB mstr_standard
J 0
(-7325 5000);
DISPLAY 0.723404 (-7325 5000);
PAINT MONO (-7325 5000);
DISPLAY INVISIBLE (-7325 5000);
FORCEPROP 1 LAST BODY_TYPE PLUMBING
J 2
(-7325 5050);
DISPLAY 0.872340 (-7325 5050);
PAINT GREEN (-7325 5050);
DISPLAY INVISIBLE (-7325 5050);
FORCEPROP 1 LAST HDL_TAP TRUE
J 2
(-7650 4875);
DISPLAY 0.872340 (-7650 4875);
DISPLAY INVISIBLE (-7650 4875);
FORCEPROP 1 LAST PATH I91
J 2
(-7323 5000);
DISPLAY 0.872340 (-7323 5000);
PAINT GREEN (-7323 5000);
DISPLAY INVISIBLE (-7323 5000);
FORCEADD TAP..1
R 2
(-7325 5150);
FORCEPROP 3 LASTPIN (-7275 5150) SIG_NAME M_G_CPU0_SA_CA<1>
J 0
(-7265 5160);
DISPLAY 0.659574 (-7265 5160);
PAINT MONO (-7265 5160);
DISPLAY INVISIBLE (-7265 5160);
FORCEPROP 1 LASTPIN (-7275 5150) BN 1
J 2
(-7263 5158);
DISPLAY 0.489362 (-7263 5158);
PAINT GREEN (-7263 5158);
FORCEPROP 2 LAST CDS_LIB mstr_standard
J 0
(-7325 5150);
DISPLAY 0.723404 (-7325 5150);
PAINT MONO (-7325 5150);
DISPLAY INVISIBLE (-7325 5150);
FORCEPROP 1 LAST BODY_TYPE PLUMBING
J 2
(-7325 5200);
DISPLAY 0.872340 (-7325 5200);
PAINT GREEN (-7325 5200);
DISPLAY INVISIBLE (-7325 5200);
FORCEPROP 1 LAST HDL_TAP TRUE
J 2
(-7650 5025);
DISPLAY 0.872340 (-7650 5025);
DISPLAY INVISIBLE (-7650 5025);
FORCEPROP 1 LAST PATH I92
J 2
(-7323 5150);
DISPLAY 0.872340 (-7323 5150);
PAINT GREEN (-7323 5150);
DISPLAY INVISIBLE (-7323 5150);
FORCEADD TAP..1
R 2
(-7325 5100);
FORCEPROP 3 LASTPIN (-7275 5100) SIG_NAME M_G_CPU0_SA_CA<0>
J 0
(-7265 5110);
DISPLAY 0.659574 (-7265 5110);
PAINT MONO (-7265 5110);
DISPLAY INVISIBLE (-7265 5110);
FORCEPROP 1 LASTPIN (-7275 5100) BN 0
J 2
(-7263 5108);
DISPLAY 0.489362 (-7263 5108);
PAINT GREEN (-7263 5108);
FORCEPROP 2 LAST CDS_LIB mstr_standard
J 0
(-7325 5100);
DISPLAY 0.723404 (-7325 5100);
PAINT MONO (-7325 5100);
DISPLAY INVISIBLE (-7325 5100);
FORCEPROP 1 LAST BODY_TYPE PLUMBING
J 2
(-7325 5150);
DISPLAY 0.872340 (-7325 5150);
PAINT GREEN (-7325 5150);
DISPLAY INVISIBLE (-7325 5150);
FORCEPROP 1 LAST HDL_TAP TRUE
J 2
(-7650 4975);
DISPLAY 0.872340 (-7650 4975);
DISPLAY INVISIBLE (-7650 4975);
FORCEPROP 1 LAST PATH I93
J 2
(-7323 5100);
DISPLAY 0.872340 (-7323 5100);
PAINT GREEN (-7323 5100);
DISPLAY INVISIBLE (-7323 5100);
FORCEADD TAP..1
R 2
(-7325 5200);
FORCEPROP 3 LASTPIN (-7275 5200) SIG_NAME M_G_CPU0_SA_CA<2>
J 0
(-7265 5210);
DISPLAY 0.659574 (-7265 5210);
PAINT MONO (-7265 5210);
DISPLAY INVISIBLE (-7265 5210);
FORCEPROP 1 LASTPIN (-7275 5200) BN 2
J 2
(-7263 5208);
DISPLAY 0.489362 (-7263 5208);
PAINT GREEN (-7263 5208);
FORCEPROP 2 LAST CDS_LIB mstr_standard
J 0
(-7325 5200);
DISPLAY 0.723404 (-7325 5200);
PAINT MONO (-7325 5200);
DISPLAY INVISIBLE (-7325 5200);
FORCEPROP 1 LAST BODY_TYPE PLUMBING
J 2
(-7325 5250);
DISPLAY 0.872340 (-7325 5250);
PAINT GREEN (-7325 5250);
DISPLAY INVISIBLE (-7325 5250);
FORCEPROP 1 LAST HDL_TAP TRUE
J 2
(-7650 5075);
DISPLAY 0.872340 (-7650 5075);
DISPLAY INVISIBLE (-7650 5075);
FORCEPROP 1 LAST PATH I94
J 2
(-7323 5200);
DISPLAY 0.872340 (-7323 5200);
PAINT GREEN (-7323 5200);
DISPLAY INVISIBLE (-7323 5200);
FORCEADD TAP..1
R 2
(-7325 5250);
FORCEPROP 3 LASTPIN (-7275 5250) SIG_NAME M_G_CPU0_SA_CA<3>
J 0
(-7265 5260);
DISPLAY 0.659574 (-7265 5260);
PAINT MONO (-7265 5260);
DISPLAY INVISIBLE (-7265 5260);
FORCEPROP 1 LASTPIN (-7275 5250) BN 3
J 2
(-7263 5258);
DISPLAY 0.489362 (-7263 5258);
PAINT GREEN (-7263 5258);
FORCEPROP 2 LAST CDS_LIB mstr_standard
J 0
(-7325 5250);
DISPLAY 0.723404 (-7325 5250);
PAINT MONO (-7325 5250);
DISPLAY INVISIBLE (-7325 5250);
FORCEPROP 1 LAST BODY_TYPE PLUMBING
J 2
(-7325 5300);
DISPLAY 0.872340 (-7325 5300);
PAINT GREEN (-7325 5300);
DISPLAY INVISIBLE (-7325 5300);
FORCEPROP 1 LAST HDL_TAP TRUE
J 2
(-7650 5125);
DISPLAY 0.872340 (-7650 5125);
DISPLAY INVISIBLE (-7650 5125);
FORCEPROP 1 LAST PATH I95
J 2
(-7323 5250);
DISPLAY 0.872340 (-7323 5250);
PAINT GREEN (-7323 5250);
DISPLAY INVISIBLE (-7323 5250);
FORCEADD TAP..1
R 2
(-7325 5300);
FORCEPROP 3 LASTPIN (-7275 5300) SIG_NAME M_G_CPU0_SA_CA<4>
J 0
(-7265 5310);
DISPLAY 0.659574 (-7265 5310);
PAINT MONO (-7265 5310);
DISPLAY INVISIBLE (-7265 5310);
FORCEPROP 1 LASTPIN (-7275 5300) BN 4
J 2
(-7263 5308);
DISPLAY 0.489362 (-7263 5308);
PAINT GREEN (-7263 5308);
FORCEPROP 2 LAST CDS_LIB mstr_standard
J 0
(-7325 5300);
DISPLAY 0.723404 (-7325 5300);
PAINT MONO (-7325 5300);
DISPLAY INVISIBLE (-7325 5300);
FORCEPROP 1 LAST BODY_TYPE PLUMBING
J 2
(-7325 5350);
DISPLAY 0.872340 (-7325 5350);
PAINT GREEN (-7325 5350);
DISPLAY INVISIBLE (-7325 5350);
FORCEPROP 1 LAST HDL_TAP TRUE
J 2
(-7650 5175);
DISPLAY 0.872340 (-7650 5175);
DISPLAY INVISIBLE (-7650 5175);
FORCEPROP 1 LAST PATH I96
J 2
(-7323 5300);
DISPLAY 0.872340 (-7323 5300);
PAINT GREEN (-7323 5300);
DISPLAY INVISIBLE (-7323 5300);
FORCEADD TAP..1
R 2
(-7325 5350);
FORCEPROP 3 LASTPIN (-7275 5350) SIG_NAME M_G_CPU0_SA_CA<5>
J 0
(-7265 5360);
DISPLAY 0.659574 (-7265 5360);
PAINT MONO (-7265 5360);
DISPLAY INVISIBLE (-7265 5360);
FORCEPROP 1 LASTPIN (-7275 5350) BN 5
J 2
(-7263 5358);
DISPLAY 0.489362 (-7263 5358);
PAINT GREEN (-7263 5358);
FORCEPROP 2 LAST CDS_LIB mstr_standard
J 0
(-7325 5350);
DISPLAY 0.723404 (-7325 5350);
PAINT MONO (-7325 5350);
DISPLAY INVISIBLE (-7325 5350);
FORCEPROP 1 LAST BODY_TYPE PLUMBING
J 2
(-7325 5400);
DISPLAY 0.872340 (-7325 5400);
PAINT GREEN (-7325 5400);
DISPLAY INVISIBLE (-7325 5400);
FORCEPROP 1 LAST HDL_TAP TRUE
J 2
(-7650 5225);
DISPLAY 0.872340 (-7650 5225);
DISPLAY INVISIBLE (-7650 5225);
FORCEPROP 1 LAST PATH I97
J 2
(-7323 5350);
DISPLAY 0.872340 (-7323 5350);
PAINT GREEN (-7323 5350);
DISPLAY INVISIBLE (-7323 5350);
FORCEADD TAP..1
R 2
(-7325 5400);
FORCEPROP 3 LASTPIN (-7275 5400) SIG_NAME M_G_CPU0_SA_CA<6>
J 0
(-7265 5410);
DISPLAY 0.659574 (-7265 5410);
PAINT MONO (-7265 5410);
DISPLAY INVISIBLE (-7265 5410);
FORCEPROP 1 LASTPIN (-7275 5400) BN 6
J 2
(-7263 5408);
DISPLAY 0.489362 (-7263 5408);
PAINT GREEN (-7263 5408);
FORCEPROP 2 LAST CDS_LIB mstr_standard
J 0
(-7325 5400);
DISPLAY 0.723404 (-7325 5400);
PAINT MONO (-7325 5400);
DISPLAY INVISIBLE (-7325 5400);
FORCEPROP 1 LAST BODY_TYPE PLUMBING
J 2
(-7325 5450);
DISPLAY 0.872340 (-7325 5450);
PAINT GREEN (-7325 5450);
DISPLAY INVISIBLE (-7325 5450);
FORCEPROP 1 LAST HDL_TAP TRUE
J 2
(-7650 5275);
DISPLAY 0.872340 (-7650 5275);
DISPLAY INVISIBLE (-7650 5275);
FORCEPROP 1 LAST PATH I98
J 2
(-7323 5400);
DISPLAY 0.872340 (-7323 5400);
PAINT GREEN (-7323 5400);
DISPLAY INVISIBLE (-7323 5400);
FORCEADD TAP..1
(-5625 4150);
FORCEPROP 3 LASTPIN (-5675 4150) SIG_NAME M_G_CPU0_SA_DQ<6>
J 0
(-5665 4160);
DISPLAY 0.659574 (-5665 4160);
PAINT MONO (-5665 4160);
DISPLAY INVISIBLE (-5665 4160);
FORCEPROP 1 LASTPIN (-5675 4150) BN 6
J 0
(-5687 4158);
DISPLAY 0.489362 (-5687 4158);
PAINT GREEN (-5687 4158);
FORCEPROP 2 LAST CDS_LIB mstr_standard
J 0
(-5625 4150);
DISPLAY 0.723404 (-5625 4150);
PAINT MONO (-5625 4150);
DISPLAY INVISIBLE (-5625 4150);
FORCEPROP 1 LAST BODY_TYPE PLUMBING
J 0
(-5625 4200);
DISPLAY 0.872340 (-5625 4200);
PAINT GREEN (-5625 4200);
DISPLAY INVISIBLE (-5625 4200);
FORCEPROP 1 LAST HDL_TAP TRUE
J 0
(-5300 4025);
DISPLAY 0.872340 (-5300 4025);
DISPLAY INVISIBLE (-5300 4025);
FORCEPROP 1 LAST PATH I99
J 0
(-5627 4150);
DISPLAY 0.872340 (-5627 4150);
PAINT GREEN (-5627 4150);
DISPLAY INVISIBLE (-5627 4150);
FORCEADD DNS..2
(-1800 1350);
PAINT RED (-1800 1350);
FORCEPROP 2 LAST CDS_LIB mstr_misc
J 0
(-1800 1350);
DISPLAY INVISIBLE (-1800 1350);
FORCEPROP 1 LAST COMMENT_BODY TRUE
R 1
J 0
(-1725 1125);
DISPLAY 0.872340 (-1725 1125);
PAINT PEACH (-1725 1125);
DISPLAY INVISIBLE (-1725 1125);
FORCEADD DNS..2
(-8200 2300);
PAINT RED (-8200 2300);
FORCEPROP 2 LAST CDS_LIB mstr_misc
J 0
(-8200 2300);
DISPLAY INVISIBLE (-8200 2300);
FORCEPROP 1 LAST COMMENT_BODY TRUE
R 1
J 0
(-8125 2075);
DISPLAY 0.872340 (-8125 2075);
PAINT PEACH (-8125 2075);
DISPLAY INVISIBLE (-8125 2075);
FORCEADD DNS..2
(-8550 2325);
PAINT RED (-8550 2325);
FORCEPROP 2 LAST CDS_LIB mstr_misc
J 0
(-8550 2325);
DISPLAY INVISIBLE (-8550 2325);
FORCEPROP 1 LAST COMMENT_BODY TRUE
R 1
J 0
(-8475 2100);
DISPLAY 0.872340 (-8475 2100);
PAINT PEACH (-8475 2100);
DISPLAY INVISIBLE (-8475 2100);
FORCEADD QUANTA_TITLE_BLOCK_C..1
(0 0);
FORCEPROP 0 LAST CDS_CON_LAST_MODIFIED Thu Sep 14 16:12:07 2023
J 0
(-1885 15);
DISPLAY INVISIBLE (-1885 15);
FORCEPROP 1 LAST CUSTOM_TXT_CDS <CON_LAST_MODIFIED>
J 0
(-1885 15);
DISPLAY 0.978723 (-1885 15);
FORCEPROP 2 LAST CUSTOM_TXT_CDS <XR_PAGE_TITLE>
J 0
(-7890 5250);
DISPLAY 0.638298 (-7890 5250);
PAINT PINK (-7890 5250);
DISPLAY INVISIBLE (-7890 5250);
FORCEPROP 1 LAST CUSTOM_TXT_CDS <NAME_2>
J 0
(-3175 50);
FORCEPROP 1 LAST CUSTOM_TXT_CDS <NAME_1>
J 0
(-3175 175);
FORCEPROP 1 LAST CUSTOM_TXT_CDS <Q_NUMBER>
J 0
(-1403 103);
DISPLAY 1.212766 (-1403 103);
FORCEPROP 1 LAST CUSTOM_TXT_CDS <Q_PROJ>
J 0
(-2382 102);
DISPLAY 1.212766 (-2382 102);
FORCEPROP 1 LAST CUSTOM_TXT_CDS <Q_REV>
J 0
(-184 103);
DISPLAY 1.212766 (-184 103);
FORCEPROP 1 LAST CUSTOM_TXT_CDS <CON_PAGE_NUM> OF <CON_TOTAL_PAGES>
J 0
(-446 18);
DISPLAY 0.978723 (-446 18);
FORCEPROP 1 LAST Q_TITLE DDR5 - CPU0 CHG
J 0
(-9300 50);
DISPLAY 2.446809 (-9300 50);
PAINT GREEN (-9300 50);
FORCEPROP 2 LAST PAGE_BORDER TRUE
J 0
(-7890 5250);
DISPLAY 0.638298 (-7890 5250);
PAINT PINK (-7890 5250);
DISPLAY INVISIBLE (-7890 5250);
FORCEPROP 2 LAST CDS_LIB pure_quanta
J 0
(0 0);
DISPLAY INVISIBLE (0 0);
FORCEPROP 1 LAST CDS_LMAN_SYM_OUTLINE -9475,6775,100,-125
J 0
(0 0);
DISPLAY 0.468085 (0 0);
PAINT GREEN (0 0);
DISPLAY INVISIBLE (0 0);
FORCEPROP 2 LAST CDS_XR_PAGE_TITLE CR-92 : @T6G_MB_LIB.T6G(SCH_1):PAGE92
J 0
(-7890 5250);
DISPLAY 0.638298 (-7890 5250);
PAINT PINK (-7890 5250);
DISPLAY INVISIBLE (-7890 5250);
FORCEPROP 1 LAST Q_DEPT BU9
J 1
(-3763 49);
DISPLAY 1.957447 (-3763 49);
PAINT GREEN (-3763 49);
DISPLAY INVISIBLE (-3763 49);
FORCEPROP 1 LAST COMMENT_BODY TRUE
J 0
(12 -13);
DISPLAY 0.978723 (12 -13);
PAINT GREEN (12 -13);
DISPLAY INVISIBLE (12 -13);
FORCEADD DNS..2
(-3750 1200);
PAINT RED (-3750 1200);
FORCEPROP 2 LAST CDS_LIB mstr_misc
J 0
(-3750 1200);
DISPLAY INVISIBLE (-3750 1200);
FORCEPROP 1 LAST COMMENT_BODY TRUE
R 1
J 0
(-3675 975);
DISPLAY 0.872340 (-3675 975);
PAINT PEACH (-3675 975);
DISPLAY INVISIBLE (-3675 975);
WIRE 17 -1 (-5575 5225)(-5575 5175);
WIRE 17 -1 (-5575 5275)(-5575 5225);
WIRE 17 -1 (-5575 5175)(-5575 5125);
WIRE 17 -1 (-5575 5125)(-5575 5075);
WIRE 17 -1 (-5575 5325)(-5575 5275);
WIRE 17 -1 (-5575 5375)(-5575 5325);
WIRE 17 -1 (-5575 5075)(-5575 5025);
WIRE 17 -1 (-5575 5025)(-5575 4975);
WIRE 17 -1 (-5575 5425)(-5575 5375);
WIRE 17 -1 (-5575 5450)(-5575 5425);
WIRE 17 -1 (-5575 4975)(-5575 4925);
WIRE 17 -1 (-5575 4925)(-5575 4875);
WIRE 17 -1 (-5575 5450)(-5075 5450);
FORCEPROP 2 LAST SIG_NAME M_G_CPU0_SA_DQ<31:0>
J 2
(-5075 5460);
DISPLAY 0.489362 (-5075 5460);
WIRE 17 -1 (-7375 5125)(-7375 5175);
WIRE 17 -1 (-7375 5175)(-7375 5225);
WIRE 17 -1 (-7375 5225)(-7375 5275);
WIRE 17 -1 (-7375 5275)(-7375 5325);
WIRE 17 -1 (-7375 5325)(-7375 5375);
WIRE 17 -1 (-7375 5375)(-7375 5425);
WIRE 17 -1 (-7375 5425)(-7375 5450);
WIRE 17 -1 (-7375 5450)(-7875 5450);
FORCEPROP 2 LAST SIG_NAME M_G_CPU0_SA_CA<6:0>
J 0
(-7875 5460);
DISPLAY 0.489362 (-7875 5460);
WIRE 17 -1 (-7375 4975)(-7375 5025);
WIRE 17 -1 (-7375 4925)(-7375 4975);
WIRE 17 -1 (-7375 5025)(-7375 5050);
WIRE 17 -1 (-7375 5050)(-7875 5050);
FORCEPROP 2 LAST SIG_NAME M_G_CPU0_SB_CA<6:0>
J 0
(-7875 5060);
DISPLAY 0.489362 (-7875 5060);
WIRE 17 -1 (-7375 4875)(-7375 4925);
WIRE 17 -1 (-7375 4825)(-7375 4875);
WIRE 17 -1 (-7375 4775)(-7375 4825);
WIRE 17 -1 (-7375 4725)(-7375 4775);
WIRE 17 -1 (-5575 4475)(-5575 4525);
WIRE 17 -1 (-5575 4475)(-5575 4425);
WIRE 17 -1 (-5575 4525)(-5575 4575);
WIRE 17 -1 (-5575 4575)(-5575 4625);
WIRE 17 -1 (-5575 4425)(-5575 4375);
WIRE 17 -1 (-5575 4375)(-5575 4325);
WIRE 17 -1 (-5575 4625)(-5575 4675);
WIRE 17 -1 (-5575 4725)(-5575 4675);
WIRE 17 -1 (-5575 4325)(-5575 4275);
WIRE 17 -1 (-5575 4275)(-5575 4225);
WIRE 17 -1 (-5575 4775)(-5575 4725);
WIRE 17 -1 (-5575 4825)(-5575 4775);
WIRE 17 -1 (-5575 4225)(-5575 4175);
WIRE 17 -1 (-5575 4175)(-5575 4125);
WIRE 17 -1 (-5575 4875)(-5575 4825);
WIRE 17 -1 (-5575 4125)(-5575 4075);
WIRE 17 -1 (-5575 4025)(-5575 4075);
WIRE 17 -1 (-5575 3975)(-5575 4025);
WIRE 17 -1 (-5575 3925)(-5575 3975);
WIRE 17 -1 (-5575 3875)(-5575 3925);
WIRE 17 -1 (-3050 3550)(-3050 3450);
WIRE 17 -1 (-3050 3575)(-3050 3550);
WIRE 17 -1 (-3050 3450)(-3050 3350);
WIRE 17 -1 (-3050 3350)(-3050 3250);
WIRE 17 -1 (-3050 3575)(-2350 3575);
FORCEPROP 2 LAST SIG_NAME M_G_CPU0_SB_DQS_DP<9:0>
J 2
(-2350 3585);
DISPLAY 0.489362 (-2350 3585);
WIRE 17 -1 (-2850 3525)(-2850 3500);
WIRE 17 -1 (-2850 3525)(-2350 3525);
FORCEPROP 2 LAST SIG_NAME M_G_CPU0_SB_DQS_DN<9:0>
J 2
(-2350 3535);
DISPLAY 0.489362 (-2350 3535);
WIRE 17 -1 (-3050 4625)(-3050 4600);
WIRE 17 -1 (-3050 4625)(-2350 4625);
FORCEPROP 2 LAST SIG_NAME M_G_CPU0_SA_DQS_DP<9:0>
J 0
(-2885 4635);
DISPLAY 0.489362 (-2885 4635);
WIRE 17 -1 (-2850 4575)(-2850 4550);
WIRE 17 -1 (-2850 4575)(-2350 4575);
FORCEPROP 2 LAST SIG_NAME M_G_CPU0_SA_DQS_DN<9:0>
J 0
(-2885 4585);
DISPLAY 0.489362 (-2885 4585);
WIRE 17 -1 (-3050 4600)(-3050 4500);
WIRE 17 -1 (-3050 4500)(-3050 4400);
WIRE 17 -1 (-3050 4400)(-3050 4300);
WIRE 17 -1 (-2850 4550)(-2850 4450);
WIRE 17 -1 (-2850 4450)(-2850 4350);
WIRE 17 -1 (-2850 4350)(-2850 4250);
WIRE 17 -1 (-2850 3400)(-2850 3300);
WIRE 17 -1 (-2850 3500)(-2850 3400);
WIRE 17 -1 (-2850 3300)(-2850 3200);
WIRE 17 -1 (-2850 3200)(-2850 3100);
WIRE 17 -1 (-3050 4300)(-3050 4200);
WIRE 17 -1 (-3050 3250)(-3050 3150);
WIRE 17 -1 (-3050 3050)(-3050 3150);
WIRE 17 -1 (-3050 2950)(-3050 3050);
WIRE 17 -1 (-3050 2850)(-3050 2950);
WIRE 17 -1 (-2850 3000)(-2850 3100);
WIRE 17 -1 (-2850 2900)(-2850 3000);
WIRE 17 -1 (-2850 2800)(-2850 2900);
WIRE 17 -1 (-2850 4250)(-2850 4150);
WIRE 17 -1 (-2850 4050)(-2850 4150);
WIRE 17 -1 (-2850 3950)(-2850 4050);
WIRE 17 -1 (-2850 3850)(-2850 3950);
WIRE 17 -1 (-3050 2850)(-3050 2750);
WIRE 17 -1 (-2850 2800)(-2850 2700);
WIRE 17 -1 (-3050 4100)(-3050 4200);
WIRE 17 -1 (-3050 4000)(-3050 4100);
WIRE 17 -1 (-3050 3900)(-3050 4000);
WIRE 17 -1 (-3050 3900)(-3050 3800);
WIRE 17 -1 (-2850 3850)(-2850 3750);
WIRE 17 -1 (-3050 2750)(-3050 2650);
WIRE 17 -1 (-2850 2700)(-2850 2600);
WIRE 17 -1 (-3050 3800)(-3050 3700);
WIRE 17 -1 (-2850 3750)(-2850 3650);
WIRE 17 -1 (-5575 2225)(-5575 2275);
WIRE 17 -1 (-5575 2275)(-5575 2325);
WIRE 17 -1 (-5575 2325)(-5575 2375);
WIRE 17 -1 (-5575 2375)(-5575 2425);
WIRE 17 -1 (-5575 2475)(-5575 2425);
WIRE 17 -1 (-5575 2525)(-5575 2475);
WIRE 17 -1 (-5575 2575)(-5575 2525);
WIRE 17 -1 (-5575 2625)(-5575 2575);
WIRE 17 -1 (-5575 2675)(-5575 2625);
WIRE 17 -1 (-5575 2725)(-5575 2675);
WIRE 17 -1 (-5575 2775)(-5575 2725);
WIRE 17 -1 (-5575 2825)(-5575 2775);
WIRE 17 -1 (-5575 2825)(-5575 2875);
WIRE 17 -1 (-5575 2875)(-5575 2925);
WIRE 17 -1 (-5575 2925)(-5575 2975);
WIRE 17 -1 (-5575 2975)(-5575 3025);
WIRE 17 -1 (-5575 3075)(-5575 3025);
WIRE 17 -1 (-5575 3125)(-5575 3075);
WIRE 17 -1 (-5575 3175)(-5575 3125);
WIRE 17 -1 (-5575 3225)(-5575 3175);
WIRE 17 -1 (-5575 3275)(-5575 3225);
WIRE 17 -1 (-5575 3325)(-5575 3275);
WIRE 17 -1 (-5575 3375)(-5575 3325);
WIRE 17 -1 (-5575 3425)(-5575 3375);
WIRE 17 -1 (-5575 3475)(-5575 3425);
WIRE 17 -1 (-5575 3525)(-5575 3475);
WIRE 17 -1 (-5575 3575)(-5575 3525);
WIRE 17 -1 (-5575 3625)(-5575 3575);
WIRE 17 -1 (-5575 3675)(-5575 3625);
WIRE 17 -1 (-5575 3725)(-5575 3675);
WIRE 17 -1 (-5575 3775)(-5575 3725);
WIRE 17 -1 (-5575 3800)(-5575 3775);
WIRE 17 -1 (-5575 3800)(-5075 3800);
FORCEPROP 2 LAST SIG_NAME M_G_CPU0_SB_DQ<31:0>
J 2
(-5075 3810);
DISPLAY 0.489362 (-5075 3810);
WIRE 17 -1 (-7375 3225)(-7375 3275);
WIRE 17 -1 (-7375 3275)(-7375 3325);
WIRE 17 -1 (-7375 3325)(-7375 3375);
WIRE 17 -1 (-7375 3375)(-7375 3425);
WIRE 17 -1 (-7375 3475)(-7375 3425);
WIRE 17 -1 (-7375 3475)(-7375 3525);
WIRE 17 -1 (-7375 3575)(-7375 3525);
WIRE 17 -1 (-7375 3575)(-7375 3600);
WIRE 17 -1 (-7375 3600)(-7875 3600);
FORCEPROP 2 LAST SIG_NAME M_G_CPU0_SB_CB<7:0>
J 0
(-7875 3610);
DISPLAY 0.489362 (-7875 3610);
WIRE 17 -1 (-7375 3675)(-7375 3725);
WIRE 17 -1 (-7375 3725)(-7375 3775);
WIRE 17 -1 (-7375 3775)(-7375 3825);
WIRE 17 -1 (-7375 3825)(-7375 3875);
WIRE 17 -1 (-7375 3925)(-7375 3875);
WIRE 17 -1 (-7375 3925)(-7375 3975);
WIRE 17 -1 (-7375 4025)(-7375 3975);
WIRE 17 -1 (-7375 4025)(-7375 4050);
WIRE 17 -1 (-7375 4050)(-7875 4050);
FORCEPROP 2 LAST SIG_NAME M_G_CPU0_SA_CB<7:0>
J 0
(-7875 4060);
DISPLAY 0.489362 (-7875 4060);
WIRE 16 -1 (-6025 1025)(-6025 1100);
WIRE 16 -1 (-8500 3050)(-8500 3125);
WIRE 16 -1 (-8225 2400)(-8225 2425);
WIRE 16 -1 (-8475 2400)(-8475 2425);
WIRE 16 -1 (-8750 1400)(-8750 1550);
WIRE 16 -1 (-7875 2850)(-7850 2850);
WIRE 16 -1 (-7875 2775)(-7875 2850);
WIRE 16 -1 (-7875 2775)(-8400 2775);
FORCEPROP 2 LAST SIG_NAME I3C_SPD_DDRGL_CPU0_SDA
J 0
(-8410 2785);
DISPLAY 0.489362 (-8410 2785);
WIRE 16 -1 (-7075 2900)(-8075 2900);
FORCEPROP 2 LAST SIG_NAME PD_CHG_CPU0_DIMM0_SAA
J 0
(-8075 2910);
DISPLAY 0.489362 (-8075 2910);
WIRE 16 -1 (-8500 3325)(-8500 3350);
WIRE 16 -1 (-8500 3350)(-8400 3350);
WIRE 16 -1 (-8400 3400)(-8400 3350);
WIRE 16 -1 (-8400 3350)(-8400 2950);
WIRE 16 -1 (-8400 2950)(-7075 2950);
WIRE 16 -1 (-5675 3250)(-5875 3250);
WIRE 16 -1 (-5675 3500)(-5875 3500);
WIRE 16 -1 (-7075 3950)(-7275 3950);
WIRE 16 -1 (-7475 2650)(-7950 2650);
FORCEPROP 2 LAST SIG_NAME I3C_SPD_DDRGL_CPU0_SCL
J 0
(-8010 2660);
DISPLAY 0.489362 (-8010 2660);
WIRE 16 -1 (-7075 2850)(-7650 2850);
FORCEPROP 2 LAST SIG_NAME I3C_SPD_DDRG_CPU0_SDA
J 0
(-7585 2860);
DISPLAY 0.446809 (-7585 2860);
FORCEPROP 2 LASTPROP $XRERR UNIQUE?
J 0
(-7825 2860);
DISPLAY 0.638298 (-7825 2860);
PAINT MONO (-7825 2860);
DISPLAY INVISIBLE (-7825 2860);
WIRE 16 -1 (-7875 2150)(-7875 2550);
WIRE 16 -1 (-7875 2150)(-8225 2150);
WIRE 16 -1 (-7075 2550)(-7875 2550);
FORCEPROP 2 LAST SIG_NAME PWRGD_CHG_CPU0_DIMM0
J 0
(-7735 2560);
DISPLAY 0.489362 (-7735 2560);
FORCEPROP 2 LASTPROP $XRERR UNIQUE?
J 0
(-7975 2560);
DISPLAY 0.638298 (-7975 2560);
PAINT MONO (-7975 2560);
DISPLAY INVISIBLE (-7975 2560);
WIRE 16 -1 (-8225 2200)(-8225 2150);
WIRE 16 -1 (-8225 2150)(-8250 2150);
WIRE 16 -1 (-1775 2100)(-1975 2100);
WIRE 16 -1 (-1975 2100)(-1975 2050);
WIRE 16 -1 (-1975 2150)(-1975 2100);
WIRE 16 -1 (-1775 2150)(-1975 2150);
WIRE 16 -1 (-1975 2200)(-1975 2150);
WIRE 16 -1 (-1775 2050)(-1975 2050);
WIRE 16 -1 (-1975 2050)(-1975 1950);
WIRE 16 -1 (-1775 2200)(-1975 2200);
WIRE 16 -1 (-1975 2250)(-1975 2200);
WIRE 16 -1 (-1775 2250)(-1975 2250);
WIRE 16 -1 (-1975 2300)(-1975 2250);
WIRE 16 -1 (-1775 2300)(-1975 2300);
WIRE 16 -1 (-1975 2350)(-1975 2300);
WIRE 16 -1 (-1775 2350)(-1975 2350);
WIRE 16 -1 (-1975 2400)(-1975 2350);
WIRE 16 -1 (-1775 2400)(-1975 2400);
WIRE 16 -1 (-1975 2450)(-1975 2400);
WIRE 16 -1 (-1775 2450)(-1975 2450);
WIRE 16 -1 (-1975 2500)(-1975 2450);
WIRE 16 -1 (-1775 2500)(-1975 2500);
WIRE 16 -1 (-1975 2550)(-1975 2500);
WIRE 16 -1 (-1975 2600)(-1975 2550);
WIRE 16 -1 (-1775 2550)(-1975 2550);
WIRE 16 -1 (-1775 2600)(-1975 2600);
WIRE 16 -1 (-1975 2650)(-1975 2600);
WIRE 16 -1 (-1775 2650)(-1975 2650);
WIRE 16 -1 (-1975 2700)(-1975 2650);
WIRE 16 -1 (-1775 2700)(-1975 2700);
WIRE 16 -1 (-1975 2750)(-1975 2700);
WIRE 16 -1 (-1775 2750)(-1975 2750);
WIRE 16 -1 (-1975 2800)(-1975 2750);
WIRE 16 -1 (-1775 2800)(-1975 2800);
WIRE 16 -1 (-1975 2850)(-1975 2800);
WIRE 16 -1 (-1775 2850)(-1975 2850);
WIRE 16 -1 (-1975 2900)(-1975 2850);
WIRE 16 -1 (-1775 2900)(-1975 2900);
WIRE 16 -1 (-1975 2950)(-1975 2900);
WIRE 16 -1 (-1775 2950)(-1975 2950);
WIRE 16 -1 (-1975 3000)(-1975 2950);
WIRE 16 -1 (-1775 3000)(-1975 3000);
WIRE 16 -1 (-1975 3050)(-1975 3000);
WIRE 16 -1 (-1975 3100)(-1975 3050);
WIRE 16 -1 (-1775 3050)(-1975 3050);
WIRE 16 -1 (-1775 3100)(-1975 3100);
WIRE 16 -1 (-1975 3150)(-1975 3100);
WIRE 16 -1 (-1775 3150)(-1975 3150);
WIRE 16 -1 (-1975 3200)(-1975 3150);
WIRE 16 -1 (-1775 3200)(-1975 3200);
WIRE 16 -1 (-1975 3250)(-1975 3200);
WIRE 16 -1 (-1775 3250)(-1975 3250);
WIRE 16 -1 (-1975 3300)(-1975 3250);
WIRE 16 -1 (-1775 3300)(-1975 3300);
WIRE 16 -1 (-1975 3350)(-1975 3300);
WIRE 16 -1 (-1775 3350)(-1975 3350);
WIRE 16 -1 (-1975 3400)(-1975 3350);
WIRE 16 -1 (-1775 3400)(-1975 3400);
WIRE 16 -1 (-1975 3450)(-1975 3400);
WIRE 16 -1 (-1775 3450)(-1975 3450);
WIRE 16 -1 (-1975 3500)(-1975 3450);
WIRE 16 -1 (-1775 3500)(-1975 3500);
WIRE 16 -1 (-1975 3550)(-1975 3500);
WIRE 16 -1 (-1975 3600)(-1975 3550);
WIRE 16 -1 (-1775 3550)(-1975 3550);
WIRE 16 -1 (-1775 3600)(-1975 3600);
WIRE 16 -1 (-1975 3650)(-1975 3600);
WIRE 16 -1 (-1775 3650)(-1975 3650);
WIRE 16 -1 (-1975 3700)(-1975 3650);
WIRE 16 -1 (-1775 3700)(-1975 3700);
WIRE 16 -1 (-1975 3750)(-1975 3700);
WIRE 16 -1 (-1775 3750)(-1975 3750);
WIRE 16 -1 (-1975 3800)(-1975 3750);
WIRE 16 -1 (-1775 3800)(-1975 3800);
WIRE 16 -1 (-1975 3850)(-1975 3800);
WIRE 16 -1 (-1775 3850)(-1975 3850);
WIRE 16 -1 (-1975 3900)(-1975 3850);
WIRE 16 -1 (-1775 3900)(-1975 3900);
WIRE 16 -1 (-1975 3950)(-1975 3900);
WIRE 16 -1 (-1775 3950)(-1975 3950);
WIRE 16 -1 (-1975 4000)(-1975 3950);
WIRE 16 -1 (-1775 4000)(-1975 4000);
WIRE 16 -1 (-1975 4050)(-1975 4000);
WIRE 16 -1 (-1975 4100)(-1975 4050);
WIRE 16 -1 (-1775 4050)(-1975 4050);
WIRE 16 -1 (-1775 4100)(-1975 4100);
WIRE 16 -1 (-1975 4150)(-1975 4100);
WIRE 16 -1 (-1775 4150)(-1975 4150);
WIRE 16 -1 (-1975 4200)(-1975 4150);
WIRE 16 -1 (-1775 4200)(-1975 4200);
WIRE 16 -1 (-1975 4250)(-1975 4200);
WIRE 16 -1 (-1775 4250)(-1975 4250);
WIRE 16 -1 (-1975 4300)(-1975 4250);
WIRE 16 -1 (-1775 4300)(-1975 4300);
WIRE 16 -1 (-1975 4350)(-1975 4300);
WIRE 16 -1 (-1775 4350)(-1975 4350);
WIRE 16 -1 (-1975 4400)(-1975 4350);
WIRE 16 -1 (-1775 4400)(-1975 4400);
WIRE 16 -1 (-1975 4450)(-1975 4400);
WIRE 16 -1 (-1775 4450)(-1975 4450);
WIRE 16 -1 (-1975 4500)(-1975 4450);
WIRE 16 -1 (-1775 4500)(-1975 4500);
WIRE 16 -1 (-1975 4550)(-1975 4500);
WIRE 16 -1 (-1775 4550)(-1975 4550);
WIRE 16 -1 (-1975 4600)(-1975 4550);
WIRE 16 -1 (-1975 4650)(-1975 4600);
WIRE 16 -1 (-1775 4600)(-1975 4600);
WIRE 16 -1 (-1775 4650)(-1975 4650);
WIRE 16 -1 (-1975 4700)(-1975 4650);
WIRE 16 -1 (-1775 4700)(-1975 4700);
WIRE 16 -1 (-1975 4750)(-1975 4700);
WIRE 16 -1 (-1775 4750)(-1975 4750);
WIRE 16 -1 (-1975 4800)(-1975 4750);
WIRE 16 -1 (-1775 4800)(-1975 4800);
WIRE 16 -1 (-1975 4850)(-1975 4800);
WIRE 16 -1 (-1775 4850)(-1975 4850);
WIRE 16 -1 (-1975 4900)(-1975 4850);
WIRE 16 -1 (-1775 4900)(-1975 4900);
WIRE 16 -1 (-1975 4950)(-1975 4900);
WIRE 16 -1 (-1775 4950)(-1975 4950);
WIRE 16 -1 (-1975 5000)(-1975 4950);
WIRE 16 -1 (-1775 5000)(-1975 5000);
WIRE 16 -1 (-1975 5050)(-1975 5000);
WIRE 16 -1 (-1775 5050)(-1975 5050);
WIRE 16 -1 (-1975 5100)(-1975 5050);
WIRE 16 -1 (-1975 5150)(-1975 5100);
WIRE 16 -1 (-1775 5100)(-1975 5100);
WIRE 16 -1 (-1775 5150)(-1975 5150);
WIRE 16 -1 (-375 2150)(-375 2050);
WIRE 16 -1 (-375 2200)(-375 2150);
WIRE 16 -1 (-375 2150)(-575 2150);
WIRE 16 -1 (-375 2050)(-575 2050);
WIRE 16 -1 (-375 2050)(-375 2000);
WIRE 16 -1 (-375 2000)(-375 1950);
WIRE 16 -1 (-375 2000)(-575 2000);
WIRE 16 -1 (-375 2250)(-375 2200);
WIRE 16 -1 (-375 2200)(-575 2200);
WIRE 16 -1 (-375 2300)(-375 2250);
WIRE 16 -1 (-375 2250)(-575 2250);
WIRE 16 -1 (-375 1950)(-375 1750);
WIRE 16 -1 (-375 1950)(-575 1950);
WIRE 16 -1 (-375 2350)(-375 2300);
WIRE 16 -1 (-375 2300)(-575 2300);
WIRE 16 -1 (-375 2400)(-375 2350);
WIRE 16 -1 (-375 2350)(-575 2350);
WIRE 16 -1 (-375 2450)(-375 2400);
WIRE 16 -1 (-375 2400)(-575 2400);
WIRE 16 -1 (-375 2500)(-375 2450);
WIRE 16 -1 (-375 2450)(-575 2450);
WIRE 16 -1 (-375 2550)(-375 2500);
WIRE 16 -1 (-375 2500)(-575 2500);
WIRE 16 -1 (-375 2600)(-375 2550);
WIRE 16 -1 (-375 2550)(-575 2550);
WIRE 16 -1 (-375 2650)(-375 2600);
WIRE 16 -1 (-375 2600)(-575 2600);
WIRE 16 -1 (-375 2700)(-375 2650);
WIRE 16 -1 (-375 2650)(-575 2650);
WIRE 16 -1 (-375 2750)(-375 2700);
WIRE 16 -1 (-375 2700)(-575 2700);
WIRE 16 -1 (-375 2800)(-375 2750);
WIRE 16 -1 (-375 2750)(-575 2750);
WIRE 16 -1 (-375 2850)(-375 2800);
WIRE 16 -1 (-375 2800)(-575 2800);
WIRE 16 -1 (-375 2900)(-375 2850);
WIRE 16 -1 (-375 2850)(-575 2850);
WIRE 16 -1 (-375 2950)(-375 2900);
WIRE 16 -1 (-375 2900)(-575 2900);
WIRE 16 -1 (-375 3000)(-375 2950);
WIRE 16 -1 (-375 2950)(-575 2950);
WIRE 16 -1 (-375 3050)(-375 3000);
WIRE 16 -1 (-375 3000)(-575 3000);
WIRE 16 -1 (-375 3100)(-375 3050);
WIRE 16 -1 (-375 3050)(-575 3050);
WIRE 16 -1 (-375 3150)(-375 3100);
WIRE 16 -1 (-375 3100)(-575 3100);
WIRE 16 -1 (-375 3200)(-375 3150);
WIRE 16 -1 (-375 3150)(-575 3150);
WIRE 16 -1 (-375 3250)(-375 3200);
WIRE 16 -1 (-375 3200)(-575 3200);
WIRE 16 -1 (-375 3300)(-375 3250);
WIRE 16 -1 (-375 3250)(-575 3250);
WIRE 16 -1 (-375 3350)(-375 3300);
WIRE 16 -1 (-375 3300)(-575 3300);
WIRE 16 -1 (-375 3400)(-375 3350);
WIRE 16 -1 (-375 3350)(-575 3350);
WIRE 16 -1 (-375 3450)(-375 3400);
WIRE 16 -1 (-375 3400)(-575 3400);
WIRE 16 -1 (-375 3500)(-375 3450);
WIRE 16 -1 (-375 3450)(-575 3450);
WIRE 16 -1 (-375 3550)(-375 3500);
WIRE 16 -1 (-375 3500)(-575 3500);
WIRE 16 -1 (-375 3600)(-375 3550);
WIRE 16 -1 (-375 3550)(-575 3550);
WIRE 16 -1 (-375 3650)(-375 3600);
WIRE 16 -1 (-375 3600)(-575 3600);
WIRE 16 -1 (-375 3700)(-375 3650);
WIRE 16 -1 (-375 3650)(-575 3650);
WIRE 16 -1 (-375 3750)(-375 3700);
WIRE 16 -1 (-375 3700)(-575 3700);
WIRE 16 -1 (-375 3800)(-375 3750);
WIRE 16 -1 (-375 3750)(-575 3750);
WIRE 16 -1 (-375 3850)(-375 3800);
WIRE 16 -1 (-375 3800)(-575 3800);
WIRE 16 -1 (-375 3900)(-375 3850);
WIRE 16 -1 (-375 3850)(-575 3850);
WIRE 16 -1 (-375 3950)(-375 3900);
WIRE 16 -1 (-375 3900)(-575 3900);
WIRE 16 -1 (-375 4000)(-375 3950);
WIRE 16 -1 (-375 3950)(-575 3950);
WIRE 16 -1 (-375 4050)(-375 4000);
WIRE 16 -1 (-375 4000)(-575 4000);
WIRE 16 -1 (-375 4100)(-375 4050);
WIRE 16 -1 (-375 4050)(-575 4050);
WIRE 16 -1 (-375 4150)(-375 4100);
WIRE 16 -1 (-375 4100)(-575 4100);
WIRE 16 -1 (-375 4200)(-375 4150);
WIRE 16 -1 (-375 4150)(-575 4150);
WIRE 16 -1 (-375 4250)(-375 4200);
WIRE 16 -1 (-375 4200)(-575 4200);
WIRE 16 -1 (-375 4300)(-375 4250);
WIRE 16 -1 (-375 4250)(-575 4250);
WIRE 16 -1 (-375 4350)(-375 4300);
WIRE 16 -1 (-375 4300)(-575 4300);
WIRE 16 -1 (-375 4400)(-375 4350);
WIRE 16 -1 (-375 4350)(-575 4350);
WIRE 16 -1 (-375 4450)(-375 4400);
WIRE 16 -1 (-375 4400)(-575 4400);
WIRE 16 -1 (-375 4500)(-375 4450);
WIRE 16 -1 (-375 4450)(-575 4450);
WIRE 16 -1 (-375 4550)(-375 4500);
WIRE 16 -1 (-375 4500)(-575 4500);
WIRE 16 -1 (-375 4600)(-375 4550);
WIRE 16 -1 (-375 4550)(-575 4550);
WIRE 16 -1 (-375 4650)(-375 4600);
WIRE 16 -1 (-375 4600)(-575 4600);
WIRE 16 -1 (-375 4700)(-375 4650);
WIRE 16 -1 (-375 4650)(-575 4650);
WIRE 16 -1 (-375 4750)(-375 4700);
WIRE 16 -1 (-375 4700)(-575 4700);
WIRE 16 -1 (-375 4800)(-375 4750);
WIRE 16 -1 (-375 4750)(-575 4750);
WIRE 16 -1 (-375 4850)(-375 4800);
WIRE 16 -1 (-375 4800)(-575 4800);
WIRE 16 -1 (-375 4900)(-375 4850);
WIRE 16 -1 (-375 4850)(-575 4850);
WIRE 16 -1 (-375 4950)(-375 4900);
WIRE 16 -1 (-375 4900)(-575 4900);
WIRE 16 -1 (-375 5000)(-375 4950);
WIRE 16 -1 (-375 4950)(-575 4950);
WIRE 16 -1 (-375 5050)(-375 5000);
WIRE 16 -1 (-375 5000)(-575 5000);
WIRE 16 -1 (-375 5100)(-375 5050);
WIRE 16 -1 (-375 5050)(-575 5050);
WIRE 16 -1 (-375 5150)(-375 5100);
WIRE 16 -1 (-375 5100)(-575 5100);
WIRE 16 -1 (-375 5200)(-375 5150);
WIRE 16 -1 (-375 5150)(-575 5150);
WIRE 16 -1 (-375 5250)(-375 5200);
WIRE 16 -1 (-375 5200)(-575 5200);
WIRE 16 -1 (-375 5300)(-375 5250);
WIRE 16 -1 (-375 5250)(-575 5250);
WIRE 16 -1 (-375 5300)(-575 5300);
WIRE 16 -1 (-2100 5650)(-2100 5775);
WIRE 16 -1 (-2100 5650)(-2675 5650);
WIRE 16 -1 (-2675 5650)(-2675 5775);
WIRE 16 -1 (-2675 5650)(-2675 5575);
WIRE 16 -1 (-2100 6075)(-1975 6075);
WIRE 16 -1 (-2100 6075)(-2100 5975);
WIRE 16 -1 (-2100 6075)(-2675 6075);
WIRE 16 -1 (-1975 5300)(-1975 6075);
WIRE 16 -1 (-1775 5300)(-1975 5300);
WIRE 16 -1 (-1975 5250)(-1975 5300);
WIRE 16 -1 (-2675 5975)(-2675 6075);
WIRE 16 -1 (-2675 6075)(-2675 6150);
WIRE 16 -1 (-1775 5250)(-1975 5250);
WIRE 16 -1 (-1975 5200)(-1975 5250);
WIRE 16 -1 (-1775 5200)(-1975 5200);
WIRE 16 -1 (-4375 1250)(-3875 1250);
WIRE 16 -1 (-4375 1400)(-4375 1250);
WIRE 16 -1 (-1150 1300)(-1150 1225);
WIRE 16 -1 (-1150 1225)(-1700 1225);
WIRE 16 -1 (-7075 3100)(-7875 3100);
FORCEPROP 2 LAST SIG_NAME M_G_CPU0_RESET_N
J 0
(-7860 3110);
DISPLAY 0.489362 (-7860 3110);
WIRE 16 -1 (-7075 3050)(-7875 3050);
FORCEPROP 2 LAST SIG_NAME M_G_CPU0_ALERT_N
J 0
(-7860 3060);
DISPLAY 0.489362 (-7860 3060);
WIRE 16 -1 (-7075 2800)(-7175 2800);
FORCEPROP 2 LAST SIG_NAME I3C_SPD_DDRG_CPU0_SCL
J 0
(-7560 2810);
DISPLAY 0.446809 (-7560 2810);
FORCEPROP 2 LASTPROP $XRERR UNIQUE?
J 0
(-7800 2810);
DISPLAY 0.638298 (-7800 2810);
PAINT MONO (-7800 2810);
DISPLAY INVISIBLE (-7800 2810);
WIRE 16 -1 (-7175 2800)(-7175 2650);
WIRE 16 -1 (-7175 2650)(-7275 2650);
WIRE 16 -1 (-8850 2150)(-8475 2150);
FORCEPROP 2 LAST SIG_NAME PWRGD_CHGL_CPU0
J 0
(-8835 2160);
DISPLAY 0.489362 (-8835 2160);
WIRE 16 -1 (-8475 2200)(-8475 2150);
WIRE 16 -1 (-8475 2150)(-8450 2150);
WIRE 16 -1 (-8750 900)(-7775 900);
FORCEPROP 2 LAST SIG_NAME PWRGD_CHGL_CPU0
J 0
(-8510 910);
DISPLAY 0.680851 (-8510 910);
WIRE 16 -1 (-8750 1200)(-8750 900);
WIRE 16 -1 (-3675 1250)(-3100 1250);
WIRE 16 -1 (-3100 1250)(-3100 775);
WIRE 16 -1 (-3100 775)(-2125 775);
FORCEPROP 2 LAST SIG_NAME PWRGD_CHGL_CPU0_R1
J 0
(-2835 785);
DISPLAY 0.680851 (-2835 785);
FORCEPROP 2 LASTPROP $XRERR UNIQUE?
J 0
(-3075 785);
DISPLAY 0.638298 (-3075 785);
PAINT MONO (-3075 785);
DISPLAY INVISIBLE (-3075 785);
WIRE 16 -1 (-3250 775)(-3100 775);
WIRE 16 -1 (-2125 775)(-2025 775);
WIRE 16 -1 (-2125 1225)(-2125 775);
WIRE 16 -1 (-1950 1225)(-2125 1225);
WIRE 16 -1 (-1825 775)(-775 775);
FORCEPROP 2 LAST SIG_NAME PWRGD_CHGL_CPU0_R2
J 0
(-1560 785);
DISPLAY 0.680851 (-1560 785);
WIRE 16 -1 (-7075 1950)(-7875 1950);
FORCEPROP 2 LAST SIG_NAME M_G_CPU0_SB_RSP<0>
J 0
(-7875 1960);
DISPLAY 0.489362 (-7875 1960);
WIRE 16 -1 (-6025 1375)(-6025 1300);
WIRE 16 -1 (-6025 1375)(-6750 1375);
FORCEPROP 2 LAST SIG_NAME PD_CHG_CPU0_DIMM0_SAA
J 0
(-6735 1385);
DISPLAY 0.489362 (-6735 1385);
WIRE 16 -1 (-7075 4000)(-7275 4000);
WIRE 16 -1 (-7075 3850)(-7275 3850);
WIRE 16 -1 (-7075 3700)(-7275 3700);
WIRE 16 -1 (-7075 3550)(-7275 3550);
WIRE 16 -1 (-7075 4700)(-7275 4700);
WIRE 16 -1 (-7075 5150)(-7275 5150);
WIRE 16 -1 (-7075 4750)(-7275 4750);
WIRE 16 -1 (-7075 5200)(-7275 5200);
WIRE 16 -1 (-7075 4800)(-7275 4800);
WIRE 16 -1 (-7075 5250)(-7275 5250);
WIRE 16 -1 (-7075 5300)(-7275 5300);
WIRE 16 -1 (-7075 5350)(-7275 5350);
WIRE 16 -1 (-7075 5400)(-7275 5400);
WIRE 16 -1 (-7075 3900)(-7275 3900);
WIRE 16 -1 (-7075 3800)(-7275 3800);
WIRE 16 -1 (-7075 3750)(-7275 3750);
WIRE 16 -1 (-7075 3650)(-7275 3650);
WIRE 16 -1 (-7075 3500)(-7275 3500);
WIRE 16 -1 (-7075 3450)(-7275 3450);
WIRE 16 -1 (-7075 3400)(-7275 3400);
WIRE 16 -1 (-7075 3350)(-7275 3350);
WIRE 16 -1 (-7075 3300)(-7275 3300);
WIRE 16 -1 (-7075 3250)(-7275 3250);
WIRE 16 -1 (-7075 3200)(-7275 3200);
WIRE 16 -1 (-7075 4100)(-7875 4100);
FORCEPROP 2 LAST SIG_NAME M_G_CPU0_CLK_DN<0>
J 0
(-7875 4110);
DISPLAY 0.489362 (-7875 4110);
WIRE 16 -1 (-7075 4150)(-7875 4150);
FORCEPROP 2 LAST SIG_NAME M_G_CPU0_CLK_DP<0>
J 0
(-7875 4160);
DISPLAY 0.489362 (-7875 4160);
WIRE 16 -1 (-7075 4400)(-7875 4400);
FORCEPROP 2 LAST SIG_NAME M_G_CPU0_SA_CS_N<0>
J 0
(-7875 4410);
DISPLAY 0.489362 (-7875 4410);
WIRE 16 -1 (-7075 4250)(-7875 4250);
FORCEPROP 2 LAST SIG_NAME M_G_CPU0_SB_CS_N<0>
J 0
(-7875 4260);
DISPLAY 0.489362 (-7875 4260);
WIRE 16 -1 (-7075 4300)(-7875 4300);
FORCEPROP 2 LAST SIG_NAME M_G_CPU0_SB_CS_N<1>
J 0
(-7875 4310);
DISPLAY 0.489362 (-7875 4310);
WIRE 16 -1 (-5675 5300)(-5875 5300);
WIRE 16 -1 (-5675 5250)(-5875 5250);
WIRE 16 -1 (-5875 5200)(-5675 5200);
WIRE 16 -1 (-5675 4550)(-5875 4550);
WIRE 16 -1 (-5675 4150)(-5875 4150);
WIRE 16 -1 (-5675 4100)(-5875 4100);
WIRE 16 -1 (-5675 4050)(-5875 4050);
WIRE 16 -1 (-5875 4000)(-5675 4000);
WIRE 16 -1 (-5675 3950)(-5875 3950);
WIRE 16 -1 (-5675 3900)(-5875 3900);
WIRE 16 -1 (-5675 3850)(-5875 3850);
WIRE 16 -1 (-5875 3750)(-5675 3750);
WIRE 16 -1 (-5675 3700)(-5875 3700);
WIRE 16 -1 (-5675 3650)(-5875 3650);
WIRE 16 -1 (-5675 3600)(-5875 3600);
WIRE 16 -1 (-5875 3550)(-5675 3550);
WIRE 16 -1 (-5675 3450)(-5875 3450);
WIRE 16 -1 (-5675 3400)(-5875 3400);
WIRE 16 -1 (-5875 3350)(-5675 3350);
WIRE 16 -1 (-5675 3300)(-5875 3300);
WIRE 16 -1 (-5675 3200)(-5875 3200);
WIRE 16 -1 (-5875 3150)(-5675 3150);
WIRE 16 -1 (-5675 3100)(-5875 3100);
WIRE 16 -1 (-5675 3050)(-5875 3050);
WIRE 16 -1 (-5675 3000)(-5875 3000);
WIRE 16 -1 (-5875 2950)(-5675 2950);
WIRE 16 -1 (-5675 2900)(-5875 2900);
WIRE 16 -1 (-5675 2850)(-5875 2850);
WIRE 16 -1 (-5675 2800)(-5875 2800);
WIRE 16 -1 (-5875 2750)(-5675 2750);
WIRE 16 -1 (-5675 2700)(-5875 2700);
WIRE 16 -1 (-5675 2650)(-5875 2650);
WIRE 16 -1 (-5675 2600)(-5875 2600);
WIRE 16 -1 (-5875 2550)(-5675 2550);
WIRE 16 -1 (-5675 2500)(-5875 2500);
WIRE 16 -1 (-5675 2450)(-5875 2450);
WIRE 16 -1 (-5675 2400)(-5875 2400);
WIRE 16 -1 (-5875 2350)(-5675 2350);
WIRE 16 -1 (-5675 2300)(-5875 2300);
WIRE 16 -1 (-5675 2250)(-5875 2250);
WIRE 16 -1 (-5675 2200)(-5875 2200);
WIRE 16 -1 (-7075 4600)(-7875 4600);
FORCEPROP 2 LAST SIG_NAME M_G_CPU0_SA_PAR
J 0
(-7875 4610);
DISPLAY 0.489362 (-7875 4610);
WIRE 16 -1 (-7075 4550)(-7875 4550);
FORCEPROP 2 LAST SIG_NAME M_G_CPU0_SB_PAR
J 0
(-7875 4560);
DISPLAY 0.489362 (-7875 4560);
WIRE 16 -1 (-5875 5400)(-5675 5400);
WIRE 16 -1 (-5675 5350)(-5875 5350);
WIRE 16 -1 (-5675 5100)(-5875 5100);
WIRE 16 -1 (-5675 5050)(-5875 5050);
WIRE 16 -1 (-5875 5000)(-5675 5000);
WIRE 16 -1 (-5675 4950)(-5875 4950);
WIRE 16 -1 (-3350 4325)(-2950 4325);
WIRE 16 -1 (-3150 4275)(-3350 4275);
WIRE 16 -1 (-3150 3425)(-3350 3425);
WIRE 16 -1 (-3350 3375)(-2950 3375);
WIRE 16 -1 (-3150 3325)(-3350 3325);
WIRE 16 -1 (-3350 3625)(-2950 3625);
WIRE 16 -1 (-3150 3675)(-3350 3675);
WIRE 16 -1 (-3350 2575)(-2950 2575);
WIRE 16 -1 (-3150 2625)(-3350 2625);
WIRE 16 -1 (-3350 3725)(-2950 3725);
WIRE 16 -1 (-3350 3775)(-3150 3775);
WIRE 16 -1 (-3350 2675)(-2950 2675);
WIRE 16 -1 (-3350 2725)(-3150 2725);
WIRE 16 -1 (-3350 3825)(-2950 3825);
WIRE 16 -1 (-3150 3875)(-3350 3875);
WIRE 16 -1 (-3350 2775)(-2950 2775);
WIRE 16 -1 (-3150 2825)(-3350 2825);
WIRE 16 -1 (-3350 3925)(-2950 3925);
WIRE 16 -1 (-3150 3975)(-3350 3975);
WIRE 16 -1 (-3350 2875)(-2950 2875);
WIRE 16 -1 (-3150 2925)(-3350 2925);
WIRE 16 -1 (-3350 4025)(-2950 4025);
WIRE 16 -1 (-3150 4075)(-3350 4075);
WIRE 16 -1 (-3350 2975)(-2950 2975);
WIRE 16 -1 (-3150 3025)(-3350 3025);
WIRE 16 -1 (-3350 4125)(-2950 4125);
WIRE 16 -1 (-3350 4175)(-3150 4175);
WIRE 16 -1 (-3350 3075)(-2950 3075);
WIRE 16 -1 (-3350 3125)(-3150 3125);
WIRE 16 -1 (-3350 4225)(-2950 4225);
WIRE 16 -1 (-3350 3175)(-2950 3175);
WIRE 16 -1 (-3150 3225)(-3350 3225);
WIRE 16 -1 (-3150 4375)(-3350 4375);
WIRE 16 -1 (-3350 3275)(-2950 3275);
WIRE 16 -1 (-3350 4425)(-2950 4425);
WIRE 16 -1 (-3150 4475)(-3350 4475);
WIRE 16 -1 (-3350 4525)(-2950 4525);
WIRE 16 -1 (-3350 4575)(-3150 4575);
WIRE 16 -1 (-3350 3475)(-2950 3475);
WIRE 16 -1 (-3350 3525)(-3150 3525);
WIRE 16 -1 (-5875 4800)(-5675 4800);
WIRE 16 -1 (-5675 4850)(-5875 4850);
WIRE 16 -1 (-5675 4900)(-5875 4900);
WIRE 16 -1 (-5875 4200)(-5675 4200);
WIRE 16 -1 (-5675 4250)(-5875 4250);
WIRE 16 -1 (-5675 4300)(-5875 4300);
WIRE 16 -1 (-5675 4350)(-5875 4350);
WIRE 16 -1 (-5875 4400)(-5675 4400);
WIRE 16 -1 (-5675 4750)(-5875 4750);
WIRE 16 -1 (-5675 4700)(-5875 4700);
WIRE 16 -1 (-5675 4650)(-5875 4650);
WIRE 16 -1 (-5875 4600)(-5675 4600);
WIRE 16 -1 (-5675 4500)(-5875 4500);
WIRE 16 -1 (-5675 4450)(-5875 4450);
WIRE 16 -1 (-7075 4850)(-7275 4850);
WIRE 16 -1 (-7075 4900)(-7275 4900);
WIRE 16 -1 (-7075 4950)(-7275 4950);
WIRE 16 -1 (-7075 5000)(-7275 5000);
WIRE 16 -1 (-7075 5100)(-7275 5100);
WIRE 16 -1 (-5675 5150)(-5875 5150);
WIRE 16 -1 (-7075 4450)(-7875 4450);
FORCEPROP 2 LAST SIG_NAME M_G_CPU0_SA_CS_N<1>
J 0
(-7875 4460);
DISPLAY 0.489362 (-7875 4460);
WIRE 16 -1 (-7075 2000)(-7875 2000);
FORCEPROP 2 LAST SIG_NAME M_G_CPU0_SA_RSP<0>
J 0
(-7875 2010);
DISPLAY 0.489362 (-7875 2010);
WIRE 16 -1 (-4200 775)(-3450 775);
FORCEPROP 2 LAST SIG_NAME PWRGD_CHGL_CPU0
J 0
(-4110 785);
DISPLAY 0.680851 (-4110 785);
DOT 1 (-8475 2150);
DOT 1 (-2125 775);
DOT 1 (-375 5200);
DOT 1 (-375 5150);
DOT 1 (-375 5100);
DOT 1 (-375 5050);
DOT 1 (-375 5000);
DOT 1 (-375 4950);
DOT 1 (-375 4850);
DOT 1 (-375 4900);
DOT 1 (-375 4750);
DOT 1 (-375 4800);
DOT 1 (-375 4700);
DOT 1 (-375 4650);
DOT 1 (-375 4600);
DOT 1 (-375 4450);
DOT 1 (-375 4500);
DOT 1 (-375 4550);
DOT 1 (-375 4400);
DOT 1 (-375 4350);
DOT 1 (-375 4300);
DOT 1 (-375 4250);
DOT 1 (-375 4200);
DOT 1 (-1975 5300);
DOT 1 (-1975 5250);
DOT 1 (-1975 5100);
DOT 1 (-1975 5000);
DOT 1 (-1975 5050);
DOT 1 (-1975 4850);
DOT 1 (-1975 4900);
DOT 1 (-1975 4700);
DOT 1 (-1975 4750);
DOT 1 (-1975 4800);
DOT 1 (-1975 4650);
DOT 1 (-1975 4600);
DOT 1 (-1975 4550);
DOT 1 (-1975 4450);
DOT 1 (-1975 4500);
DOT 1 (-1975 4400);
DOT 1 (-1975 4350);
DOT 1 (-1975 4300);
DOT 1 (-1975 4250);
DOT 1 (-1975 4200);
DOT 1 (-375 4150);
DOT 1 (-375 4100);
DOT 1 (-375 4050);
DOT 1 (-375 4000);
DOT 1 (-375 3950);
DOT 1 (-375 3900);
DOT 1 (-375 3850);
DOT 1 (-375 3800);
DOT 1 (-375 3700);
DOT 1 (-375 3750);
DOT 1 (-375 3600);
DOT 1 (-375 3650);
DOT 1 (-375 3550);
DOT 1 (-375 3450);
DOT 1 (-375 3500);
DOT 1 (-375 3300);
DOT 1 (-375 3350);
DOT 1 (-375 3400);
DOT 1 (-375 3200);
DOT 1 (-375 3250);
DOT 1 (-375 3150);
DOT 1 (-375 3100);
DOT 1 (-375 3050);
DOT 1 (-375 3000);
DOT 1 (-375 2950);
DOT 1 (-375 2900);
DOT 1 (-375 2800);
DOT 1 (-375 2850);
DOT 1 (-375 2750);
DOT 1 (-375 2700);
DOT 1 (-375 2650);
DOT 1 (-375 2600);
DOT 1 (-375 2550);
DOT 1 (-375 2500);
DOT 1 (-375 2450);
DOT 1 (-375 2400);
DOT 1 (-375 2350);
DOT 1 (-375 2300);
DOT 1 (-375 2150);
DOT 1 (-375 2250);
DOT 1 (-375 2200);
DOT 1 (-375 2050);
DOT 1 (-375 1950);
DOT 1 (-375 2000);
DOT 1 (-1975 4100);
DOT 1 (-1975 4150);
DOT 1 (-1975 4050);
DOT 1 (-1975 3950);
DOT 1 (-1975 4000);
DOT 1 (-1975 3900);
DOT 1 (-1975 3850);
DOT 1 (-1975 3800);
DOT 1 (-1975 3750);
DOT 1 (-1975 3700);
DOT 1 (-1975 3550);
DOT 1 (-1975 3650);
DOT 1 (-1975 3600);
DOT 1 (-1975 3450);
DOT 1 (-1975 3500);
DOT 1 (-1975 3400);
DOT 1 (-1975 3350);
DOT 1 (-1975 3300);
DOT 1 (-1975 3250);
DOT 1 (-1975 3200);
DOT 1 (-1975 3150);
DOT 1 (-1975 3050);
DOT 1 (-1975 3100);
DOT 1 (-1975 2950);
DOT 1 (-1975 3000);
DOT 1 (-1975 2900);
DOT 1 (-1975 2800);
DOT 1 (-1975 2850);
DOT 1 (-1975 2650);
DOT 1 (-1975 2700);
DOT 1 (-1975 2750);
DOT 1 (-1975 2550);
DOT 1 (-1975 2600);
DOT 1 (-1975 2500);
DOT 1 (-1975 2400);
DOT 1 (-1975 2450);
DOT 1 (-1975 2300);
DOT 1 (-1975 2350);
DOT 1 (-1975 2150);
DOT 1 (-1975 2250);
DOT 1 (-1975 2200);
DOT 1 (-1975 2050);
DOT 1 (-1975 2100);
DOT 1 (-2675 5650);
DOT 1 (-2100 6075);
DOT 1 (-2675 6075);
DOT 1 (-1975 4950);
DOT 1 (-375 5250);
DOT 1 (-8400 3350);
DOT 1 (-8225 2150);
DOT 1 (-3100 775);
QUIT
